FILE_TYPE = MACRO_DRAWING;
SET COLOR_WIRE YELLOW;
SET COLOR_PROP MONO;
SET COLOR_DOT WHITE;
SET COLOR_ARC YELLOW;
SET COLOR_BODY GREEN;
SET COLOR_NOTE MONO;
SET PROP_DISPLAY VALUE;
SET PAGE_NUMBER P41;
FORCEADD GND..1
(-4475 550);
FORCEPROP 3 LASTPIN (-4475 600) SIG_NAME GND\g
J 0
(-4465 610);
DISPLAY 0.659574 (-4465 610);
PAINT MONO (-4465 610);
DISPLAY INVISIBLE (-4465 610);
FORCEPROP 1 LAST VOLTAGE 0.0V
J 0
(-4520 507);
DISPLAY 0.340426 (-4520 507);
PAINT SKYBLUE (-4520 507);
DISPLAY INVISIBLE (-4520 507);
FORCEPROP 1 LAST SIZE 1B
J 0
(-4400 500);
DISPLAY 1.170213 (-4400 500);
PAINT AQUA (-4400 500);
DISPLAY INVISIBLE (-4400 500);
FORCEPROP 2 LAST CDS_LIB mstr_symbols
J 0
(-4475 550);
PAINT ORANGE (-4475 550);
DISPLAY INVISIBLE (-4475 550);
FORCEPROP 1 LAST BODY_TYPE PLUMBING
J 0
(-4520 507);
DISPLAY 0.340426 (-4520 507);
PAINT GREEN (-4520 507);
DISPLAY INVISIBLE (-4520 507);
FORCEPROP 1 LAST PATH I275
J 0
(-4400 550);
DISPLAY 0.872340 (-4400 550);
PAINT AQUA (-4400 550);
DISPLAY INVISIBLE (-4400 550);
FORCEPROP 1 LAST HDL_POWER GND
J 0
(-4475 700);
DISPLAY 1.170213 (-4475 700);
PAINT GREEN (-4475 700);
DISPLAY INVISIBLE (-4475 700);
FORCEADD GND..1
(-2800 525);
FORCEPROP 3 LASTPIN (-2800 575) SIG_NAME GND\g
J 0
(-2790 585);
DISPLAY 0.659574 (-2790 585);
PAINT MONO (-2790 585);
DISPLAY INVISIBLE (-2790 585);
FORCEPROP 1 LAST VOLTAGE 0.0V
J 0
(-2845 482);
DISPLAY 0.340426 (-2845 482);
PAINT SKYBLUE (-2845 482);
DISPLAY INVISIBLE (-2845 482);
FORCEPROP 1 LAST SIZE 1B
J 0
(-2725 475);
DISPLAY 1.170213 (-2725 475);
PAINT AQUA (-2725 475);
DISPLAY INVISIBLE (-2725 475);
FORCEPROP 2 LAST CDS_LIB mstr_symbols
J 0
(-2800 525);
PAINT ORANGE (-2800 525);
DISPLAY INVISIBLE (-2800 525);
FORCEPROP 1 LAST BODY_TYPE PLUMBING
J 0
(-2845 482);
DISPLAY 0.340426 (-2845 482);
PAINT GREEN (-2845 482);
DISPLAY INVISIBLE (-2845 482);
FORCEPROP 1 LAST PATH I276
J 0
(-2725 525);
DISPLAY 0.872340 (-2725 525);
PAINT AQUA (-2725 525);
DISPLAY INVISIBLE (-2725 525);
FORCEPROP 1 LAST HDL_POWER GND
J 0
(-2800 675);
DISPLAY 1.170213 (-2800 675);
PAINT GREEN (-2800 675);
DISPLAY INVISIBLE (-2800 675);
FORCEADD GND..1
(-1075 475);
FORCEPROP 3 LASTPIN (-1075 525) SIG_NAME GND\g
J 0
(-1065 535);
DISPLAY 0.659574 (-1065 535);
PAINT MONO (-1065 535);
DISPLAY INVISIBLE (-1065 535);
FORCEPROP 1 LAST VOLTAGE 0.0V
J 0
(-1120 432);
DISPLAY 0.340426 (-1120 432);
PAINT SKYBLUE (-1120 432);
DISPLAY INVISIBLE (-1120 432);
FORCEPROP 1 LAST SIZE 1B
J 0
(-1000 425);
DISPLAY 1.170213 (-1000 425);
PAINT AQUA (-1000 425);
DISPLAY INVISIBLE (-1000 425);
FORCEPROP 2 LAST CDS_LIB mstr_symbols
J 0
(-1075 475);
PAINT ORANGE (-1075 475);
DISPLAY INVISIBLE (-1075 475);
FORCEPROP 1 LAST BODY_TYPE PLUMBING
J 0
(-1120 432);
DISPLAY 0.340426 (-1120 432);
PAINT GREEN (-1120 432);
DISPLAY INVISIBLE (-1120 432);
FORCEPROP 1 LAST PATH I277
J 0
(-1000 475);
DISPLAY 0.872340 (-1000 475);
PAINT AQUA (-1000 475);
DISPLAY INVISIBLE (-1000 475);
FORCEPROP 1 LAST HDL_POWER GND
J 0
(-1075 625);
DISPLAY 1.170213 (-1075 625);
PAINT GREEN (-1075 625);
DISPLAY INVISIBLE (-1075 625);
FORCEADD GND..1
(-6025 550);
FORCEPROP 3 LASTPIN (-6025 600) SIG_NAME GND\g
J 0
(-6015 610);
DISPLAY 0.659574 (-6015 610);
PAINT MONO (-6015 610);
DISPLAY INVISIBLE (-6015 610);
FORCEPROP 1 LAST VOLTAGE 0.0V
J 0
(-6070 507);
DISPLAY 0.340426 (-6070 507);
PAINT SKYBLUE (-6070 507);
DISPLAY INVISIBLE (-6070 507);
FORCEPROP 1 LAST SIZE 1B
J 0
(-5950 500);
DISPLAY 1.170213 (-5950 500);
PAINT AQUA (-5950 500);
DISPLAY INVISIBLE (-5950 500);
FORCEPROP 2 LAST CDS_LIB mstr_symbols
J 0
(-6025 550);
PAINT ORANGE (-6025 550);
DISPLAY INVISIBLE (-6025 550);
FORCEPROP 1 LAST BODY_TYPE PLUMBING
J 0
(-6070 507);
DISPLAY 0.340426 (-6070 507);
PAINT GREEN (-6070 507);
DISPLAY INVISIBLE (-6070 507);
FORCEPROP 1 LAST PATH I278
J 0
(-5950 550);
DISPLAY 0.872340 (-5950 550);
PAINT AQUA (-5950 550);
DISPLAY INVISIBLE (-5950 550);
FORCEPROP 1 LAST HDL_POWER GND
J 0
(-6025 700);
DISPLAY 1.170213 (-6025 700);
PAINT GREEN (-6025 700);
DISPLAY INVISIBLE (-6025 700);
FORCEADD GND..1
(-4350 550);
FORCEPROP 3 LASTPIN (-4350 600) SIG_NAME GND\g
J 0
(-4340 610);
DISPLAY 0.659574 (-4340 610);
PAINT MONO (-4340 610);
DISPLAY INVISIBLE (-4340 610);
FORCEPROP 1 LAST VOLTAGE 0.0V
J 0
(-4395 507);
DISPLAY 0.340426 (-4395 507);
PAINT SKYBLUE (-4395 507);
DISPLAY INVISIBLE (-4395 507);
FORCEPROP 1 LAST SIZE 1B
J 0
(-4275 500);
DISPLAY 1.170213 (-4275 500);
PAINT AQUA (-4275 500);
DISPLAY INVISIBLE (-4275 500);
FORCEPROP 2 LAST CDS_LIB mstr_symbols
J 0
(-4350 550);
PAINT ORANGE (-4350 550);
DISPLAY INVISIBLE (-4350 550);
FORCEPROP 1 LAST BODY_TYPE PLUMBING
J 0
(-4395 507);
DISPLAY 0.340426 (-4395 507);
PAINT GREEN (-4395 507);
DISPLAY INVISIBLE (-4395 507);
FORCEPROP 1 LAST PATH I279
J 0
(-4275 550);
DISPLAY 0.872340 (-4275 550);
PAINT AQUA (-4275 550);
DISPLAY INVISIBLE (-4275 550);
FORCEPROP 1 LAST HDL_POWER GND
J 0
(-4350 700);
DISPLAY 1.170213 (-4350 700);
PAINT GREEN (-4350 700);
DISPLAY INVISIBLE (-4350 700);
FORCEADD GND..1
(-2625 500);
FORCEPROP 3 LASTPIN (-2625 550) SIG_NAME GND\g
J 0
(-2615 560);
DISPLAY 0.659574 (-2615 560);
PAINT MONO (-2615 560);
DISPLAY INVISIBLE (-2615 560);
FORCEPROP 1 LAST VOLTAGE 0.0V
J 0
(-2670 457);
DISPLAY 0.340426 (-2670 457);
PAINT SKYBLUE (-2670 457);
DISPLAY INVISIBLE (-2670 457);
FORCEPROP 1 LAST SIZE 1B
J 0
(-2550 450);
DISPLAY 1.170213 (-2550 450);
PAINT AQUA (-2550 450);
DISPLAY INVISIBLE (-2550 450);
FORCEPROP 2 LAST CDS_LIB mstr_symbols
J 0
(-2625 500);
PAINT ORANGE (-2625 500);
DISPLAY INVISIBLE (-2625 500);
FORCEPROP 1 LAST BODY_TYPE PLUMBING
J 0
(-2670 457);
DISPLAY 0.340426 (-2670 457);
PAINT GREEN (-2670 457);
DISPLAY INVISIBLE (-2670 457);
FORCEPROP 1 LAST PATH I280
J 0
(-2550 500);
DISPLAY 0.872340 (-2550 500);
PAINT AQUA (-2550 500);
DISPLAY INVISIBLE (-2550 500);
FORCEPROP 1 LAST HDL_POWER GND
J 0
(-2625 650);
DISPLAY 1.170213 (-2625 650);
PAINT GREEN (-2625 650);
DISPLAY INVISIBLE (-2625 650);
FORCEADD GND..1
(-925 475);
FORCEPROP 3 LASTPIN (-925 525) SIG_NAME GND\g
J 0
(-915 535);
DISPLAY 0.659574 (-915 535);
PAINT MONO (-915 535);
DISPLAY INVISIBLE (-915 535);
FORCEPROP 1 LAST VOLTAGE 0.0V
J 0
(-970 432);
DISPLAY 0.340426 (-970 432);
PAINT SKYBLUE (-970 432);
DISPLAY INVISIBLE (-970 432);
FORCEPROP 1 LAST SIZE 1B
J 0
(-850 425);
DISPLAY 1.170213 (-850 425);
PAINT AQUA (-850 425);
DISPLAY INVISIBLE (-850 425);
FORCEPROP 2 LAST CDS_LIB mstr_symbols
J 0
(-925 475);
PAINT ORANGE (-925 475);
DISPLAY INVISIBLE (-925 475);
FORCEPROP 1 LAST BODY_TYPE PLUMBING
J 0
(-970 432);
DISPLAY 0.340426 (-970 432);
PAINT GREEN (-970 432);
DISPLAY INVISIBLE (-970 432);
FORCEPROP 1 LAST PATH I281
J 0
(-850 475);
DISPLAY 0.872340 (-850 475);
PAINT AQUA (-850 475);
DISPLAY INVISIBLE (-850 475);
FORCEPROP 1 LAST HDL_POWER GND
J 0
(-925 625);
DISPLAY 1.170213 (-925 625);
PAINT GREEN (-925 625);
DISPLAY INVISIBLE (-925 625);
FORCEADD GND..1
(600 1650);
FORCEPROP 3 LASTPIN (600 1700) SIG_NAME GND\g
J 0
(610 1710);
DISPLAY 0.659574 (610 1710);
PAINT MONO (610 1710);
DISPLAY INVISIBLE (610 1710);
FORCEPROP 1 LAST VOLTAGE 0.0V
J 0
(555 1607);
DISPLAY 0.340426 (555 1607);
PAINT SKYBLUE (555 1607);
DISPLAY INVISIBLE (555 1607);
FORCEPROP 1 LAST SIZE 1B
J 0
(675 1600);
DISPLAY 1.170213 (675 1600);
PAINT AQUA (675 1600);
DISPLAY INVISIBLE (675 1600);
FORCEPROP 2 LAST CDS_LIB mstr_symbols
J 0
(600 1650);
PAINT ORANGE (600 1650);
DISPLAY INVISIBLE (600 1650);
FORCEPROP 1 LAST BODY_TYPE PLUMBING
J 0
(555 1607);
DISPLAY 0.340426 (555 1607);
PAINT GREEN (555 1607);
DISPLAY INVISIBLE (555 1607);
FORCEPROP 1 LAST PATH I282
J 0
(675 1650);
DISPLAY 0.872340 (675 1650);
PAINT AQUA (675 1650);
DISPLAY INVISIBLE (675 1650);
FORCEPROP 1 LAST HDL_POWER GND
J 0
(600 1800);
DISPLAY 1.170213 (600 1800);
PAINT GREEN (600 1800);
DISPLAY INVISIBLE (600 1800);
FORCEADD SKX_EXT_B..27
(-5275 2650);
FORCEPROP 2 LASTPIN (-4675 1650) $PN CG62
J 0
(-4665 1660);
DISPLAY 0.617021 (-4665 1660);
PAINT ORANGE (-4665 1660);
FORCEPROP 1 LAST LOCATION U5D1
J 0
(-5825 4900);
DISPLAY 0.617021 (-5825 4900);
PAINT AQUA (-5825 4900);
FORCEPROP 1 LAST PART_NUMBER TBD
J 0
(-5825 500);
DISPLAY 0.617021 (-5825 500);
PAINT BLUE (-5825 500);
FORCEPROP 1 LAST MATERIAL IC
J 0
(-5825 4850);
DISPLAY 0.617021 (-5825 4850);
PAINT SKYBLUE (-5825 4850);
FORCEPROP 2 LASTPIN (-5875 4650) $PN BG74
J 2
(-5885 4660);
DISPLAY 0.617021 (-5885 4660);
PAINT ORANGE (-5885 4660);
FORCEPROP 2 LASTPIN (-5875 4600) $PN BG76
J 2
(-5885 4610);
DISPLAY 0.617021 (-5885 4610);
PAINT ORANGE (-5885 4610);
FORCEPROP 2 LASTPIN (-5875 4550) $PN BG78
J 2
(-5885 4560);
DISPLAY 0.617021 (-5885 4560);
PAINT ORANGE (-5885 4560);
FORCEPROP 2 LASTPIN (-5875 4500) $PN BG80
J 2
(-5885 4510);
DISPLAY 0.617021 (-5885 4510);
PAINT ORANGE (-5885 4510);
FORCEPROP 2 LASTPIN (-5875 4450) $PN BG82
J 2
(-5885 4460);
DISPLAY 0.617021 (-5885 4460);
PAINT ORANGE (-5885 4460);
FORCEPROP 2 LASTPIN (-5875 4400) $PN BH7
J 2
(-5885 4410);
DISPLAY 0.617021 (-5885 4410);
PAINT ORANGE (-5885 4410);
FORCEPROP 2 LASTPIN (-5875 4350) $PN BH9
J 2
(-5885 4360);
DISPLAY 0.617021 (-5885 4360);
PAINT ORANGE (-5885 4360);
FORCEPROP 2 LASTPIN (-5875 4300) $PN BH11
J 2
(-5885 4310);
DISPLAY 0.617021 (-5885 4310);
PAINT ORANGE (-5885 4310);
FORCEPROP 2 LASTPIN (-5875 4250) $PN BH15
J 2
(-5885 4260);
DISPLAY 0.617021 (-5885 4260);
PAINT ORANGE (-5885 4260);
FORCEPROP 2 LASTPIN (-5875 4200) $PN BH21
J 2
(-5885 4210);
DISPLAY 0.617021 (-5885 4210);
PAINT ORANGE (-5885 4210);
FORCEPROP 2 LASTPIN (-5875 4150) $PN BJ4
J 2
(-5885 4160);
DISPLAY 0.617021 (-5885 4160);
PAINT ORANGE (-5885 4160);
FORCEPROP 2 LASTPIN (-5875 4100) $PN BJ6
J 2
(-5885 4110);
DISPLAY 0.617021 (-5885 4110);
PAINT ORANGE (-5885 4110);
FORCEPROP 2 LASTPIN (-5875 4050) $PN BK3
J 2
(-5885 4060);
DISPLAY 0.617021 (-5885 4060);
PAINT ORANGE (-5885 4060);
FORCEPROP 2 LASTPIN (-5875 4000) $PN BK7
J 2
(-5885 4010);
DISPLAY 0.617021 (-5885 4010);
PAINT ORANGE (-5885 4010);
FORCEPROP 2 LASTPIN (-5875 3950) $PN BK11
J 2
(-5885 3960);
DISPLAY 0.617021 (-5885 3960);
PAINT ORANGE (-5885 3960);
FORCEPROP 2 LASTPIN (-5875 3900) $PN BK19
J 2
(-5885 3910);
DISPLAY 0.617021 (-5885 3910);
PAINT ORANGE (-5885 3910);
FORCEPROP 2 LASTPIN (-5875 3850) $PN BL6
J 2
(-5885 3860);
DISPLAY 0.617021 (-5885 3860);
PAINT ORANGE (-5885 3860);
FORCEPROP 2 LASTPIN (-5875 3800) $PN BL10
J 2
(-5885 3810);
DISPLAY 0.617021 (-5885 3810);
PAINT ORANGE (-5885 3810);
FORCEPROP 2 LASTPIN (-5875 3750) $PN BL12
J 2
(-5885 3760);
DISPLAY 0.617021 (-5885 3760);
PAINT ORANGE (-5885 3760);
FORCEPROP 2 LASTPIN (-5875 3700) $PN P61
J 2
(-5885 3710);
DISPLAY 0.617021 (-5885 3710);
PAINT ORANGE (-5885 3710);
FORCEPROP 2 LASTPIN (-5875 3650) $PN BL22
J 2
(-5885 3660);
DISPLAY 0.617021 (-5885 3660);
PAINT ORANGE (-5885 3660);
FORCEPROP 2 LASTPIN (-5875 3600) $PN BL24
J 2
(-5885 3610);
DISPLAY 0.617021 (-5885 3610);
PAINT ORANGE (-5885 3610);
FORCEPROP 2 LASTPIN (-5875 3550) $PN BL64
J 2
(-5885 3560);
DISPLAY 0.617021 (-5885 3560);
PAINT ORANGE (-5885 3560);
FORCEPROP 2 LASTPIN (-5875 3500) $PN BL66
J 2
(-5885 3510);
DISPLAY 0.617021 (-5885 3510);
PAINT ORANGE (-5885 3510);
FORCEPROP 2 LASTPIN (-5875 3450) $PN BL68
J 2
(-5885 3460);
DISPLAY 0.617021 (-5885 3460);
PAINT ORANGE (-5885 3460);
FORCEPROP 2 LASTPIN (-5875 3400) $PN BL70
J 2
(-5885 3410);
DISPLAY 0.617021 (-5885 3410);
PAINT ORANGE (-5885 3410);
FORCEPROP 2 LASTPIN (-5875 3350) $PN BL72
J 2
(-5885 3360);
DISPLAY 0.617021 (-5885 3360);
PAINT ORANGE (-5885 3360);
FORCEPROP 2 LASTPIN (-5875 3300) $PN BL74
J 2
(-5885 3310);
DISPLAY 0.617021 (-5885 3310);
PAINT ORANGE (-5885 3310);
FORCEPROP 2 LASTPIN (-5875 3250) $PN BL76
J 2
(-5885 3260);
DISPLAY 0.617021 (-5885 3260);
PAINT ORANGE (-5885 3260);
FORCEPROP 2 LASTPIN (-5875 3200) $PN BL78
J 2
(-5885 3210);
DISPLAY 0.617021 (-5885 3210);
PAINT ORANGE (-5885 3210);
FORCEPROP 2 LASTPIN (-5875 3150) $PN BL80
J 2
(-5885 3160);
DISPLAY 0.617021 (-5885 3160);
PAINT ORANGE (-5885 3160);
FORCEPROP 2 LASTPIN (-5875 3100) $PN BL82
J 2
(-5885 3110);
DISPLAY 0.617021 (-5885 3110);
PAINT ORANGE (-5885 3110);
FORCEPROP 2 LASTPIN (-5875 3050) $PN BM9
J 2
(-5885 3060);
DISPLAY 0.617021 (-5885 3060);
PAINT ORANGE (-5885 3060);
FORCEPROP 2 LASTPIN (-5875 3000) $PN BM13
J 2
(-5885 3010);
DISPLAY 0.617021 (-5885 3010);
PAINT ORANGE (-5885 3010);
FORCEPROP 2 LASTPIN (-5875 2950) $PN BM15
J 2
(-5885 2960);
DISPLAY 0.617021 (-5885 2960);
PAINT ORANGE (-5885 2960);
FORCEPROP 2 LASTPIN (-5875 2900) $PN P59
J 2
(-5885 2910);
DISPLAY 0.617021 (-5885 2910);
PAINT ORANGE (-5885 2910);
FORCEPROP 2 LASTPIN (-5875 2850) $PN BM25
J 2
(-5885 2860);
DISPLAY 0.617021 (-5885 2860);
PAINT ORANGE (-5885 2860);
FORCEPROP 2 LASTPIN (-5875 2800) $PN BN6
J 2
(-5885 2810);
DISPLAY 0.617021 (-5885 2810);
PAINT ORANGE (-5885 2810);
FORCEPROP 2 LASTPIN (-5875 2750) $PN BN10
J 2
(-5885 2760);
DISPLAY 0.617021 (-5885 2760);
PAINT ORANGE (-5885 2760);
FORCEPROP 2 LASTPIN (-5875 2700) $PN BN20
J 2
(-5885 2710);
DISPLAY 0.617021 (-5885 2710);
PAINT ORANGE (-5885 2710);
FORCEPROP 2 LASTPIN (-5875 2650) $PN BN26
J 2
(-5885 2660);
DISPLAY 0.617021 (-5885 2660);
PAINT ORANGE (-5885 2660);
FORCEPROP 2 LASTPIN (-5875 2600) $PN BP3
J 2
(-5885 2610);
DISPLAY 0.617021 (-5885 2610);
PAINT ORANGE (-5885 2610);
FORCEPROP 2 LASTPIN (-5875 2550) $PN BP27
J 2
(-5885 2560);
DISPLAY 0.617021 (-5885 2560);
PAINT ORANGE (-5885 2560);
FORCEPROP 2 LASTPIN (-5875 2500) $PN BR6
J 2
(-5885 2510);
DISPLAY 0.617021 (-5885 2510);
PAINT ORANGE (-5885 2510);
FORCEPROP 2 LASTPIN (-5875 2450) $PN BR10
J 2
(-5885 2460);
DISPLAY 0.617021 (-5885 2460);
PAINT ORANGE (-5885 2460);
FORCEPROP 2 LASTPIN (-5875 2400) $PN BR16
J 2
(-5885 2410);
DISPLAY 0.617021 (-5885 2410);
PAINT ORANGE (-5885 2410);
FORCEPROP 2 LASTPIN (-5875 2350) $PN P57
J 2
(-5885 2360);
DISPLAY 0.617021 (-5885 2360);
PAINT ORANGE (-5885 2360);
FORCEPROP 2 LASTPIN (-5875 2300) $PN BR64
J 2
(-5885 2310);
DISPLAY 0.617021 (-5885 2310);
PAINT ORANGE (-5885 2310);
FORCEPROP 2 LASTPIN (-5875 2250) $PN BR66
J 2
(-5885 2260);
DISPLAY 0.617021 (-5885 2260);
PAINT ORANGE (-5885 2260);
FORCEPROP 2 LASTPIN (-5875 2200) $PN BR68
J 2
(-5885 2210);
DISPLAY 0.617021 (-5885 2210);
PAINT ORANGE (-5885 2210);
FORCEPROP 2 LASTPIN (-5875 2150) $PN BR70
J 2
(-5885 2160);
DISPLAY 0.617021 (-5885 2160);
PAINT ORANGE (-5885 2160);
FORCEPROP 2 LASTPIN (-5875 2100) $PN BR72
J 2
(-5885 2110);
DISPLAY 0.617021 (-5885 2110);
PAINT ORANGE (-5885 2110);
FORCEPROP 2 LASTPIN (-5875 2050) $PN BR74
J 2
(-5885 2060);
DISPLAY 0.617021 (-5885 2060);
PAINT ORANGE (-5885 2060);
FORCEPROP 2 LASTPIN (-5875 2000) $PN BR76
J 2
(-5885 2010);
DISPLAY 0.617021 (-5885 2010);
PAINT ORANGE (-5885 2010);
FORCEPROP 2 LASTPIN (-5875 1950) $PN BR78
J 2
(-5885 1960);
DISPLAY 0.617021 (-5885 1960);
PAINT ORANGE (-5885 1960);
FORCEPROP 2 LASTPIN (-5875 1900) $PN BR80
J 2
(-5885 1910);
DISPLAY 0.617021 (-5885 1910);
PAINT ORANGE (-5885 1910);
FORCEPROP 2 LASTPIN (-5875 1850) $PN BR82
J 2
(-5885 1860);
DISPLAY 0.617021 (-5885 1860);
PAINT ORANGE (-5885 1860);
FORCEPROP 2 LASTPIN (-5875 1800) $PN BT3
J 2
(-5885 1810);
DISPLAY 0.617021 (-5885 1810);
PAINT ORANGE (-5885 1810);
FORCEPROP 2 LASTPIN (-5875 1750) $PN BT5
J 2
(-5885 1760);
DISPLAY 0.617021 (-5885 1760);
PAINT ORANGE (-5885 1760);
FORCEPROP 2 LASTPIN (-5875 1700) $PN BT21
J 2
(-5885 1710);
DISPLAY 0.617021 (-5885 1710);
PAINT ORANGE (-5885 1710);
FORCEPROP 2 LASTPIN (-5875 1650) $PN BT23
J 2
(-5885 1660);
DISPLAY 0.617021 (-5885 1660);
PAINT ORANGE (-5885 1660);
FORCEPROP 2 LASTPIN (-5875 1600) $PN BT25
J 2
(-5885 1610);
DISPLAY 0.617021 (-5885 1610);
PAINT ORANGE (-5885 1610);
FORCEPROP 2 LASTPIN (-5875 1550) $PN BU8
J 2
(-5885 1560);
DISPLAY 0.617021 (-5885 1560);
PAINT ORANGE (-5885 1560);
FORCEPROP 2 LASTPIN (-5875 1500) $PN BV5
J 2
(-5885 1510);
DISPLAY 0.617021 (-5885 1510);
PAINT ORANGE (-5885 1510);
FORCEPROP 2 LASTPIN (-5875 1450) $PN BU10
J 2
(-5885 1460);
DISPLAY 0.617021 (-5885 1460);
PAINT ORANGE (-5885 1460);
FORCEPROP 2 LASTPIN (-5875 1400) $PN BV17
J 2
(-5885 1410);
DISPLAY 0.617021 (-5885 1410);
PAINT ORANGE (-5885 1410);
FORCEPROP 2 LASTPIN (-5875 1350) $PN BV25
J 2
(-5885 1360);
DISPLAY 0.617021 (-5885 1360);
PAINT ORANGE (-5885 1360);
FORCEPROP 2 LASTPIN (-5875 1300) $PN BW6
J 2
(-5885 1310);
DISPLAY 0.617021 (-5885 1310);
PAINT ORANGE (-5885 1310);
FORCEPROP 2 LASTPIN (-5875 1250) $PN P55
J 2
(-5885 1260);
DISPLAY 0.617021 (-5885 1260);
PAINT ORANGE (-5885 1260);
FORCEPROP 2 LASTPIN (-5875 1200) $PN BW12
J 2
(-5885 1210);
DISPLAY 0.617021 (-5885 1210);
PAINT ORANGE (-5885 1210);
FORCEPROP 2 LASTPIN (-5875 1150) $PN BW14
J 2
(-5885 1160);
DISPLAY 0.617021 (-5885 1160);
PAINT ORANGE (-5885 1160);
FORCEPROP 2 LASTPIN (-5875 1100) $PN BW16
J 2
(-5885 1110);
DISPLAY 0.617021 (-5885 1110);
PAINT ORANGE (-5885 1110);
FORCEPROP 2 LASTPIN (-5875 1050) $PN BW18
J 2
(-5885 1060);
DISPLAY 0.617021 (-5885 1060);
PAINT ORANGE (-5885 1060);
FORCEPROP 2 LASTPIN (-5875 1000) $PN BW26
J 2
(-5885 1010);
DISPLAY 0.617021 (-5885 1010);
PAINT ORANGE (-5885 1010);
FORCEPROP 2 LASTPIN (-5875 950) $PN BW72
J 2
(-5885 960);
DISPLAY 0.617021 (-5885 960);
PAINT ORANGE (-5885 960);
FORCEPROP 2 LASTPIN (-5875 900) $PN BW74
J 2
(-5885 910);
DISPLAY 0.617021 (-5885 910);
PAINT ORANGE (-5885 910);
FORCEPROP 2 LASTPIN (-5875 850) $PN BW76
J 2
(-5885 860);
DISPLAY 0.617021 (-5885 860);
PAINT ORANGE (-5885 860);
FORCEPROP 2 LASTPIN (-5875 800) $PN BW78
J 2
(-5885 810);
DISPLAY 0.617021 (-5885 810);
PAINT ORANGE (-5885 810);
FORCEPROP 2 LASTPIN (-5875 750) $PN BW80
J 2
(-5885 760);
DISPLAY 0.617021 (-5885 760);
PAINT ORANGE (-5885 760);
FORCEPROP 2 LASTPIN (-5875 700) $PN BW82
J 2
(-5885 710);
DISPLAY 0.617021 (-5885 710);
PAINT ORANGE (-5885 710);
FORCEPROP 2 LASTPIN (-4675 4650) $PN BY11
J 0
(-4665 4660);
DISPLAY 0.617021 (-4665 4660);
PAINT ORANGE (-4665 4660);
FORCEPROP 2 LASTPIN (-4675 4600) $PN BY13
J 0
(-4665 4610);
DISPLAY 0.617021 (-4665 4610);
PAINT ORANGE (-4665 4610);
FORCEPROP 2 LASTPIN (-4675 4550) $PN BY23
J 0
(-4665 4560);
DISPLAY 0.617021 (-4665 4560);
PAINT ORANGE (-4665 4560);
FORCEPROP 2 LASTPIN (-4675 4500) $PN BY63
J 0
(-4665 4510);
DISPLAY 0.617021 (-4665 4510);
PAINT ORANGE (-4665 4510);
FORCEPROP 2 LASTPIN (-4675 4450) $PN BY65
J 0
(-4665 4460);
DISPLAY 0.617021 (-4665 4460);
PAINT ORANGE (-4665 4460);
FORCEPROP 2 LASTPIN (-4675 4400) $PN BY67
J 0
(-4665 4410);
DISPLAY 0.617021 (-4665 4410);
PAINT ORANGE (-4665 4410);
FORCEPROP 2 LASTPIN (-4675 4350) $PN BY69
J 0
(-4665 4360);
DISPLAY 0.617021 (-4665 4360);
PAINT ORANGE (-4665 4360);
FORCEPROP 2 LASTPIN (-4675 4300) $PN BY71
J 0
(-4665 4310);
DISPLAY 0.617021 (-4665 4310);
PAINT ORANGE (-4665 4310);
FORCEPROP 2 LASTPIN (-4675 4250) $PN CA2
J 0
(-4665 4260);
DISPLAY 0.617021 (-4665 4260);
PAINT ORANGE (-4665 4260);
FORCEPROP 2 LASTPIN (-4675 4200) $PN CA6
J 0
(-4665 4210);
DISPLAY 0.617021 (-4665 4210);
PAINT ORANGE (-4665 4210);
FORCEPROP 2 LASTPIN (-4675 4150) $PN CA8
J 0
(-4665 4160);
DISPLAY 0.617021 (-4665 4160);
PAINT ORANGE (-4665 4160);
FORCEPROP 2 LASTPIN (-4675 4100) $PN CA10
J 0
(-4665 4110);
DISPLAY 0.617021 (-4665 4110);
PAINT ORANGE (-4665 4110);
FORCEPROP 2 LASTPIN (-4675 4050) $PN CA14
J 0
(-4665 4060);
DISPLAY 0.617021 (-4665 4060);
PAINT ORANGE (-4665 4060);
FORCEPROP 2 LASTPIN (-4675 4000) $PN CA18
J 0
(-4665 4010);
DISPLAY 0.617021 (-4665 4010);
PAINT ORANGE (-4665 4010);
FORCEPROP 2 LASTPIN (-4675 3950) $PN CA26
J 0
(-4665 3960);
DISPLAY 0.617021 (-4665 3960);
PAINT ORANGE (-4665 3960);
FORCEPROP 2 LASTPIN (-4675 3900) $PN CA64
J 0
(-4665 3910);
DISPLAY 0.617021 (-4665 3910);
PAINT ORANGE (-4665 3910);
FORCEPROP 2 LASTPIN (-4675 3850) $PN CA66
J 0
(-4665 3860);
DISPLAY 0.617021 (-4665 3860);
PAINT ORANGE (-4665 3860);
FORCEPROP 2 LASTPIN (-4675 3800) $PN CA68
J 0
(-4665 3810);
DISPLAY 0.617021 (-4665 3810);
PAINT ORANGE (-4665 3810);
FORCEPROP 2 LASTPIN (-4675 3750) $PN CA70
J 0
(-4665 3760);
DISPLAY 0.617021 (-4665 3760);
PAINT ORANGE (-4665 3760);
FORCEPROP 2 LASTPIN (-4675 3700) $PN CB7
J 0
(-4665 3710);
DISPLAY 0.617021 (-4665 3710);
PAINT ORANGE (-4665 3710);
FORCEPROP 2 LASTPIN (-4675 3650) $PN CB9
J 0
(-4665 3660);
DISPLAY 0.617021 (-4665 3660);
PAINT ORANGE (-4665 3660);
FORCEPROP 2 LASTPIN (-4675 3600) $PN CB27
J 0
(-4665 3610);
DISPLAY 0.617021 (-4665 3610);
PAINT ORANGE (-4665 3610);
FORCEPROP 2 LASTPIN (-4675 3550) $PN CB63
J 0
(-4665 3560);
DISPLAY 0.617021 (-4665 3560);
PAINT ORANGE (-4665 3560);
FORCEPROP 2 LASTPIN (-4675 3500) $PN CB71
J 0
(-4665 3510);
DISPLAY 0.617021 (-4665 3510);
PAINT ORANGE (-4665 3510);
FORCEPROP 2 LASTPIN (-4675 3450) $PN CC4
J 0
(-4665 3460);
DISPLAY 0.617021 (-4665 3460);
PAINT ORANGE (-4665 3460);
FORCEPROP 2 LASTPIN (-4675 3400) $PN CC16
J 0
(-4665 3410);
DISPLAY 0.617021 (-4665 3410);
PAINT ORANGE (-4665 3410);
FORCEPROP 2 LASTPIN (-4675 3350) $PN CC18
J 0
(-4665 3360);
DISPLAY 0.617021 (-4665 3360);
PAINT ORANGE (-4665 3360);
FORCEPROP 2 LASTPIN (-4675 3300) $PN CC24
J 0
(-4665 3310);
DISPLAY 0.617021 (-4665 3310);
PAINT ORANGE (-4665 3310);
FORCEPROP 2 LASTPIN (-4675 3250) $PN CC64
J 0
(-4665 3260);
DISPLAY 0.617021 (-4665 3260);
PAINT ORANGE (-4665 3260);
FORCEPROP 2 LASTPIN (-4675 3200) $PN CC72
J 0
(-4665 3210);
DISPLAY 0.617021 (-4665 3210);
PAINT ORANGE (-4665 3210);
FORCEPROP 2 LASTPIN (-4675 3150) $PN CC74
J 0
(-4665 3160);
DISPLAY 0.617021 (-4665 3160);
PAINT ORANGE (-4665 3160);
FORCEPROP 2 LASTPIN (-4675 3100) $PN CC76
J 0
(-4665 3110);
DISPLAY 0.617021 (-4665 3110);
PAINT ORANGE (-4665 3110);
FORCEPROP 2 LASTPIN (-4675 3050) $PN CC78
J 0
(-4665 3060);
DISPLAY 0.617021 (-4665 3060);
PAINT ORANGE (-4665 3060);
FORCEPROP 2 LASTPIN (-4675 3000) $PN CC80
J 0
(-4665 3010);
DISPLAY 0.617021 (-4665 3010);
PAINT ORANGE (-4665 3010);
FORCEPROP 2 LASTPIN (-4675 2950) $PN CC82
J 0
(-4665 2960);
DISPLAY 0.617021 (-4665 2960);
PAINT ORANGE (-4665 2960);
FORCEPROP 2 LASTPIN (-4675 2900) $PN CD5
J 0
(-4665 2910);
DISPLAY 0.617021 (-4665 2910);
PAINT ORANGE (-4665 2910);
FORCEPROP 2 LASTPIN (-4675 2850) $PN CD13
J 0
(-4665 2860);
DISPLAY 0.617021 (-4665 2860);
PAINT ORANGE (-4665 2860);
FORCEPROP 2 LASTPIN (-4675 2750) $PN CD73
J 0
(-4665 2760);
DISPLAY 0.617021 (-4665 2760);
PAINT ORANGE (-4665 2760);
FORCEPROP 2 LASTPIN (-4675 2700) $PN CD75
J 0
(-4665 2710);
DISPLAY 0.617021 (-4665 2710);
PAINT ORANGE (-4665 2710);
FORCEPROP 2 LASTPIN (-4675 2650) $PN CD77
J 0
(-4665 2660);
DISPLAY 0.617021 (-4665 2660);
PAINT ORANGE (-4665 2660);
FORCEPROP 2 LASTPIN (-4675 2600) $PN CD79
J 0
(-4665 2610);
DISPLAY 0.617021 (-4665 2610);
PAINT ORANGE (-4665 2610);
FORCEPROP 2 LASTPIN (-4675 2550) $PN CD81
J 0
(-4665 2560);
DISPLAY 0.617021 (-4665 2560);
PAINT ORANGE (-4665 2560);
FORCEPROP 2 LASTPIN (-4675 2500) $PN CE10
J 0
(-4665 2510);
DISPLAY 0.617021 (-4665 2510);
PAINT ORANGE (-4665 2510);
FORCEPROP 2 LASTPIN (-4675 2450) $PN CE14
J 0
(-4665 2460);
DISPLAY 0.617021 (-4665 2460);
PAINT ORANGE (-4665 2460);
FORCEPROP 2 LASTPIN (-4675 2400) $PN CE20
J 0
(-4665 2410);
DISPLAY 0.617021 (-4665 2410);
PAINT ORANGE (-4665 2410);
FORCEPROP 2 LASTPIN (-4675 2350) $PN CE26
J 0
(-4665 2360);
DISPLAY 0.617021 (-4665 2360);
PAINT ORANGE (-4665 2360);
FORCEPROP 2 LASTPIN (-4675 2300) $PN CE62
J 0
(-4665 2310);
DISPLAY 0.617021 (-4665 2310);
PAINT ORANGE (-4665 2310);
FORCEPROP 2 LASTPIN (-4675 2250) $PN CE70
J 0
(-4665 2260);
DISPLAY 0.617021 (-4665 2260);
PAINT ORANGE (-4665 2260);
FORCEPROP 2 LASTPIN (-4675 2200) $PN CE82
J 0
(-4665 2210);
DISPLAY 0.617021 (-4665 2210);
PAINT ORANGE (-4665 2210);
FORCEPROP 2 LASTPIN (-4675 2150) $PN P53
J 0
(-4665 2160);
DISPLAY 0.617021 (-4665 2160);
PAINT ORANGE (-4665 2160);
FORCEPROP 2 LASTPIN (-4675 2100) $PN CF9
J 0
(-4665 2110);
DISPLAY 0.617021 (-4665 2110);
PAINT ORANGE (-4665 2110);
FORCEPROP 2 LASTPIN (-4675 2050) $PN CF63
J 0
(-4665 2060);
DISPLAY 0.617021 (-4665 2060);
PAINT ORANGE (-4665 2060);
FORCEPROP 2 LASTPIN (-4675 2000) $PN CF69
J 0
(-4665 2010);
DISPLAY 0.617021 (-4665 2010);
PAINT ORANGE (-4665 2010);
FORCEPROP 2 LASTPIN (-4675 1950) $PN CF71
J 0
(-4665 1960);
DISPLAY 0.617021 (-4665 1960);
PAINT ORANGE (-4665 1960);
FORCEPROP 2 LASTPIN (-4675 1900) $PN CF77
J 0
(-4665 1910);
DISPLAY 0.617021 (-4665 1910);
PAINT ORANGE (-4665 1910);
FORCEPROP 2 LASTPIN (-4675 1850) $PN CF83
J 0
(-4665 1860);
DISPLAY 0.617021 (-4665 1860);
PAINT ORANGE (-4665 1860);
FORCEPROP 2 LASTPIN (-4675 1800) $PN P51
J 0
(-4665 1810);
DISPLAY 0.617021 (-4665 1810);
PAINT ORANGE (-4665 1810);
FORCEPROP 2 LASTPIN (-4675 1750) $PN CG18
J 0
(-4665 1760);
DISPLAY 0.617021 (-4665 1760);
PAINT ORANGE (-4665 1760);
FORCEPROP 2 LASTPIN (-4675 1700) $PN CG22
J 0
(-4665 1710);
DISPLAY 0.617021 (-4665 1710);
PAINT ORANGE (-4665 1710);
FORCEPROP 2 LASTPIN (-4675 1600) $PN CG68
J 0
(-4665 1610);
DISPLAY 0.617021 (-4665 1610);
PAINT ORANGE (-4665 1610);
FORCEPROP 2 LASTPIN (-4675 1550) $PN CG72
J 0
(-4665 1560);
DISPLAY 0.617021 (-4665 1560);
PAINT ORANGE (-4665 1560);
FORCEPROP 2 LASTPIN (-4675 1500) $PN CG80
J 0
(-4665 1510);
DISPLAY 0.617021 (-4665 1510);
PAINT ORANGE (-4665 1510);
FORCEPROP 2 LASTPIN (-4675 1450) $PN CH1
J 0
(-4665 1460);
DISPLAY 0.617021 (-4665 1460);
PAINT ORANGE (-4665 1460);
FORCEPROP 2 LASTPIN (-4675 1400) $PN CH3
J 0
(-4665 1410);
DISPLAY 0.617021 (-4665 1410);
PAINT ORANGE (-4665 1410);
FORCEPROP 2 LASTPIN (-4675 1350) $PN CH15
J 0
(-4665 1360);
DISPLAY 0.617021 (-4665 1360);
PAINT ORANGE (-4665 1360);
FORCEPROP 2 LASTPIN (-4675 1300) $PN CH19
J 0
(-4665 1310);
DISPLAY 0.617021 (-4665 1310);
PAINT ORANGE (-4665 1310);
FORCEPROP 2 LASTPIN (-4675 1250) $PN CH63
J 0
(-4665 1260);
DISPLAY 0.617021 (-4665 1260);
PAINT ORANGE (-4665 1260);
FORCEPROP 2 LASTPIN (-4675 1200) $PN CH67
J 0
(-4665 1210);
DISPLAY 0.617021 (-4665 1210);
PAINT ORANGE (-4665 1210);
FORCEPROP 2 LASTPIN (-4675 1150) $PN CH73
J 0
(-4665 1160);
DISPLAY 0.617021 (-4665 1160);
PAINT ORANGE (-4665 1160);
FORCEPROP 2 LASTPIN (-4675 1100) $PN CH79
J 0
(-4665 1110);
DISPLAY 0.617021 (-4665 1110);
PAINT ORANGE (-4665 1110);
FORCEPROP 2 LASTPIN (-4675 1050) $PN CH81
J 0
(-4665 1060);
DISPLAY 0.617021 (-4665 1060);
PAINT ORANGE (-4665 1060);
FORCEPROP 2 LASTPIN (-4675 1000) $PN CH83
J 0
(-4665 1010);
DISPLAY 0.617021 (-4665 1010);
PAINT ORANGE (-4665 1010);
FORCEPROP 2 LASTPIN (-4675 950) $PN CJ2
J 0
(-4665 960);
DISPLAY 0.617021 (-4665 960);
PAINT ORANGE (-4665 960);
FORCEPROP 2 LASTPIN (-4675 900) $PN CJ6
J 0
(-4665 910);
DISPLAY 0.617021 (-4665 910);
PAINT ORANGE (-4665 910);
FORCEPROP 2 LASTPIN (-4675 850) $PN CJ8
J 0
(-4665 860);
DISPLAY 0.617021 (-4665 860);
PAINT ORANGE (-4665 860);
FORCEPROP 2 LASTPIN (-4675 800) $PN CJ10
J 0
(-4665 810);
DISPLAY 0.617021 (-4665 810);
PAINT ORANGE (-4665 810);
FORCEPROP 2 LASTPIN (-4675 750) $PN CJ12
J 0
(-4665 760);
DISPLAY 0.617021 (-4665 760);
PAINT ORANGE (-4665 760);
FORCEPROP 2 LASTPIN (-4675 700) $PN P49
J 0
(-4665 710);
DISPLAY 0.617021 (-4665 710);
PAINT ORANGE (-4665 710);
FORCEPROP 2 LASTPIN (-4675 2800) $PN CD63
J 0
(-4665 2810);
DISPLAY 0.617021 (-4665 2810);
PAINT ORANGE (-4665 2810);
FORCEPROP 1 LAST PACK_TYPE BGA1
J 0
(-5825 4950);
PAINT SKYBLUE (-5825 4950);
DISPLAY INVISIBLE (-5825 4950);
FORCEPROP 2 LAST CDS_LIB chpset_lib
J 0
(-5275 2650);
PAINT ORANGE (-5275 2650);
DISPLAY INVISIBLE (-5275 2650);
FORCEPROP 2 LAST SEC_TYPE BGA1
J 0
(-5825 4950);
DISPLAY 1.021277 (-5825 4950);
PAINT ORANGE (-5825 4950);
DISPLAY INVISIBLE (-5825 4950);
FORCEPROP 2 LAST SEC 27
J 0
(-5825 4950);
DISPLAY 0.680851 (-5825 4950);
PAINT MONO (-5825 4950);
DISPLAY INVISIBLE (-5825 4950);
FORCEPROP 2 LAST CDS_LOCATION U5D1
J 0
(-5825 4900);
DISPLAY 0.617021 (-5825 4900);
PAINT AQUA (-5825 4900);
DISPLAY INVISIBLE (-5825 4900);
FORCEPROP 1 LAST PATH I283
J 0
(-5275 4850);
PAINT GREEN (-5275 4850);
DISPLAY INVISIBLE (-5275 4850);
FORCEPROP 0 LAST ROOM CPU0
J 0
(-5825 5000);
DISPLAY 1.021277 (-5825 5000);
PAINT ORANGE (-5825 5000);
DISPLAY INVISIBLE (-5825 5000);
FORCEADD SKX_EXT_B..28
(-3575 2650);
FORCEPROP 1 LAST LOCATION U5D1
J 0
(-4125 4900);
DISPLAY 0.617021 (-4125 4900);
PAINT AQUA (-4125 4900);
FORCEPROP 1 LAST PART_NUMBER TBD
J 0
(-4125 500);
DISPLAY 0.617021 (-4125 500);
PAINT BLUE (-4125 500);
FORCEPROP 1 LAST MATERIAL IC
J 0
(-4125 4850);
DISPLAY 0.617021 (-4125 4850);
PAINT SKYBLUE (-4125 4850);
FORCEPROP 2 LASTPIN (-4175 4650) $PN P47
J 2
(-4185 4660);
DISPLAY 0.617021 (-4185 4660);
PAINT ORANGE (-4185 4660);
FORCEPROP 2 LASTPIN (-4175 4600) $PN CJ62
J 2
(-4185 4610);
DISPLAY 0.617021 (-4185 4610);
PAINT ORANGE (-4185 4610);
FORCEPROP 2 LASTPIN (-4175 4550) $PN CJ74
J 2
(-4185 4560);
DISPLAY 0.617021 (-4185 4560);
PAINT ORANGE (-4185 4560);
FORCEPROP 2 LASTPIN (-4175 4500) $PN CJ76
J 2
(-4185 4510);
DISPLAY 0.617021 (-4185 4510);
PAINT ORANGE (-4185 4510);
FORCEPROP 2 LASTPIN (-4175 4450) $PN CJ78
J 2
(-4185 4460);
DISPLAY 0.617021 (-4185 4460);
PAINT ORANGE (-4185 4460);
FORCEPROP 2 LASTPIN (-4175 4400) $PN CJ82
J 2
(-4185 4410);
DISPLAY 0.617021 (-4185 4410);
PAINT ORANGE (-4185 4410);
FORCEPROP 2 LASTPIN (-4175 4350) $PN CJ84
J 2
(-4185 4360);
DISPLAY 0.617021 (-4185 4360);
PAINT ORANGE (-4185 4360);
FORCEPROP 2 LASTPIN (-4175 4300) $PN CJ86
J 2
(-4185 4310);
DISPLAY 0.617021 (-4185 4310);
PAINT ORANGE (-4185 4310);
FORCEPROP 2 LASTPIN (-4175 4250) $PN CK11
J 2
(-4185 4260);
DISPLAY 0.617021 (-4185 4260);
PAINT ORANGE (-4185 4260);
FORCEPROP 2 LASTPIN (-4175 4200) $PN CK15
J 2
(-4185 4210);
DISPLAY 0.617021 (-4185 4210);
PAINT ORANGE (-4185 4210);
FORCEPROP 2 LASTPIN (-4175 4150) $PN CK21
J 2
(-4185 4160);
DISPLAY 0.617021 (-4185 4160);
PAINT ORANGE (-4185 4160);
FORCEPROP 2 LASTPIN (-4175 4100) $PN CK27
J 2
(-4185 4110);
DISPLAY 0.617021 (-4185 4110);
PAINT ORANGE (-4185 4110);
FORCEPROP 2 LASTPIN (-4175 4050) $PN CK63
J 2
(-4185 4060);
DISPLAY 0.617021 (-4185 4060);
PAINT ORANGE (-4185 4060);
FORCEPROP 2 LASTPIN (-4175 4000) $PN CK65
J 2
(-4185 4010);
DISPLAY 0.617021 (-4185 4010);
PAINT ORANGE (-4185 4010);
FORCEPROP 2 LASTPIN (-4175 3950) $PN CK67
J 2
(-4185 3960);
DISPLAY 0.617021 (-4185 3960);
PAINT ORANGE (-4185 3960);
FORCEPROP 2 LASTPIN (-4175 3900) $PN CK69
J 2
(-4185 3910);
DISPLAY 0.617021 (-4185 3910);
PAINT ORANGE (-4185 3910);
FORCEPROP 2 LASTPIN (-4175 3850) $PN CK71
J 2
(-4185 3860);
DISPLAY 0.617021 (-4185 3860);
PAINT ORANGE (-4185 3860);
FORCEPROP 2 LASTPIN (-4175 3800) $PN CK73
J 2
(-4185 3810);
DISPLAY 0.617021 (-4185 3810);
PAINT ORANGE (-4185 3810);
FORCEPROP 2 LASTPIN (-4175 3750) $PN CK75
J 2
(-4185 3760);
DISPLAY 0.617021 (-4185 3760);
PAINT ORANGE (-4185 3760);
FORCEPROP 2 LASTPIN (-4175 3700) $PN CK83
J 2
(-4185 3710);
DISPLAY 0.617021 (-4185 3710);
PAINT ORANGE (-4185 3710);
FORCEPROP 2 LASTPIN (-4175 3650) $PN CK85
J 2
(-4185 3660);
DISPLAY 0.617021 (-4185 3660);
PAINT ORANGE (-4185 3660);
FORCEPROP 2 LASTPIN (-4175 3600) $PN CL8
J 2
(-4185 3610);
DISPLAY 0.617021 (-4185 3610);
PAINT ORANGE (-4185 3610);
FORCEPROP 2 LASTPIN (-4175 3550) $PN CL14
J 2
(-4185 3560);
DISPLAY 0.617021 (-4185 3560);
PAINT ORANGE (-4185 3560);
FORCEPROP 2 LASTPIN (-4175 3500) $PN CL18
J 2
(-4185 3510);
DISPLAY 0.617021 (-4185 3510);
PAINT ORANGE (-4185 3510);
FORCEPROP 2 LASTPIN (-4175 3450) $PN P45
J 2
(-4185 3460);
DISPLAY 0.617021 (-4185 3460);
PAINT ORANGE (-4185 3460);
FORCEPROP 2 LASTPIN (-4175 3400) $PN H63
J 2
(-4185 3410);
DISPLAY 0.617021 (-4185 3410);
PAINT ORANGE (-4185 3410);
FORCEPROP 2 LASTPIN (-4175 3350) $PN CL62
J 2
(-4185 3360);
DISPLAY 0.617021 (-4185 3360);
PAINT ORANGE (-4185 3360);
FORCEPROP 2 LASTPIN (-4175 3300) $PN CL64
J 2
(-4185 3310);
DISPLAY 0.617021 (-4185 3310);
PAINT ORANGE (-4185 3310);
FORCEPROP 2 LASTPIN (-4175 3250) $PN CL66
J 2
(-4185 3260);
DISPLAY 0.617021 (-4185 3260);
PAINT ORANGE (-4185 3260);
FORCEPROP 2 LASTPIN (-4175 3200) $PN CL74
J 2
(-4185 3210);
DISPLAY 0.617021 (-4185 3210);
PAINT ORANGE (-4185 3210);
FORCEPROP 2 LASTPIN (-4175 3150) $PN CL76
J 2
(-4185 3160);
DISPLAY 0.617021 (-4185 3160);
PAINT ORANGE (-4185 3160);
FORCEPROP 2 LASTPIN (-4175 3100) $PN CL78
J 2
(-4185 3110);
DISPLAY 0.617021 (-4185 3110);
PAINT ORANGE (-4185 3110);
FORCEPROP 2 LASTPIN (-4175 3050) $PN CL80
J 2
(-4185 3060);
DISPLAY 0.617021 (-4185 3060);
PAINT ORANGE (-4185 3060);
FORCEPROP 2 LASTPIN (-4175 3000) $PN CM19
J 2
(-4185 3010);
DISPLAY 0.617021 (-4185 3010);
PAINT ORANGE (-4185 3010);
FORCEPROP 2 LASTPIN (-4175 2950) $PN CM29
J 2
(-4185 2960);
DISPLAY 0.617021 (-4185 2960);
PAINT ORANGE (-4185 2960);
FORCEPROP 2 LASTPIN (-4175 2900) $PN CM5
J 2
(-4185 2910);
DISPLAY 0.617021 (-4185 2910);
PAINT ORANGE (-4185 2910);
FORCEPROP 2 LASTPIN (-4175 2850) $PN CM31
J 2
(-4185 2860);
DISPLAY 0.617021 (-4185 2860);
PAINT ORANGE (-4185 2860);
FORCEPROP 2 LASTPIN (-4175 2800) $PN CM61
J 2
(-4185 2810);
DISPLAY 0.617021 (-4185 2810);
PAINT ORANGE (-4185 2810);
FORCEPROP 2 LASTPIN (-4175 2750) $PN CM63
J 2
(-4185 2760);
DISPLAY 0.617021 (-4185 2760);
PAINT ORANGE (-4185 2760);
FORCEPROP 2 LASTPIN (-4175 2700) $PN CM67
J 2
(-4185 2710);
DISPLAY 0.617021 (-4185 2710);
PAINT ORANGE (-4185 2710);
FORCEPROP 2 LASTPIN (-4175 2650) $PN CM73
J 2
(-4185 2660);
DISPLAY 0.617021 (-4185 2660);
PAINT ORANGE (-4185 2660);
FORCEPROP 2 LASTPIN (-4175 2600) $PN CM77
J 2
(-4185 2610);
DISPLAY 0.617021 (-4185 2610);
PAINT ORANGE (-4185 2610);
FORCEPROP 2 LASTPIN (-4175 2550) $PN CM83
J 2
(-4185 2560);
DISPLAY 0.617021 (-4185 2560);
PAINT ORANGE (-4185 2560);
FORCEPROP 2 LASTPIN (-4175 2500) $PN CM85
J 2
(-4185 2510);
DISPLAY 0.617021 (-4185 2510);
PAINT ORANGE (-4185 2510);
FORCEPROP 2 LASTPIN (-4175 2450) $PN CN2
J 2
(-4185 2460);
DISPLAY 0.617021 (-4185 2460);
PAINT ORANGE (-4185 2460);
FORCEPROP 2 LASTPIN (-4175 2400) $PN CN12
J 2
(-4185 2410);
DISPLAY 0.617021 (-4185 2410);
PAINT ORANGE (-4185 2410);
FORCEPROP 2 LASTPIN (-4175 2350) $PN H61
J 2
(-4185 2360);
DISPLAY 0.617021 (-4185 2360);
PAINT ORANGE (-4185 2360);
FORCEPROP 2 LASTPIN (-4175 2300) $PN CN26
J 2
(-4185 2310);
DISPLAY 0.617021 (-4185 2310);
PAINT ORANGE (-4185 2310);
FORCEPROP 2 LASTPIN (-4175 2250) $PN CN32
J 2
(-4185 2260);
DISPLAY 0.617021 (-4185 2260);
PAINT ORANGE (-4185 2260);
FORCEPROP 2 LASTPIN (-4175 2200) $PN CN60
J 2
(-4185 2210);
DISPLAY 0.617021 (-4185 2210);
PAINT ORANGE (-4185 2210);
FORCEPROP 2 LASTPIN (-4175 2150) $PN CN62
J 2
(-4185 2160);
DISPLAY 0.617021 (-4185 2160);
PAINT ORANGE (-4185 2160);
FORCEPROP 2 LASTPIN (-4175 2100) $PN CN68
J 2
(-4185 2110);
DISPLAY 0.617021 (-4185 2110);
PAINT ORANGE (-4185 2110);
FORCEPROP 2 LASTPIN (-4175 2050) $PN CN78
J 2
(-4185 2060);
DISPLAY 0.617021 (-4185 2060);
PAINT ORANGE (-4185 2060);
FORCEPROP 2 LASTPIN (-4175 2000) $PN CP1
J 2
(-4185 2010);
DISPLAY 0.617021 (-4185 2010);
PAINT ORANGE (-4185 2010);
FORCEPROP 2 LASTPIN (-4175 1950) $PN H59
J 2
(-4185 1960);
DISPLAY 0.617021 (-4185 1960);
PAINT ORANGE (-4185 1960);
FORCEPROP 2 LASTPIN (-4175 1900) $PN CP25
J 2
(-4185 1910);
DISPLAY 0.617021 (-4185 1910);
PAINT ORANGE (-4185 1910);
FORCEPROP 2 LASTPIN (-4175 1850) $PN CP59
J 2
(-4185 1860);
DISPLAY 0.617021 (-4185 1860);
PAINT ORANGE (-4185 1860);
FORCEPROP 2 LASTPIN (-4175 1800) $PN CP69
J 2
(-4185 1810);
DISPLAY 0.617021 (-4185 1810);
PAINT ORANGE (-4185 1810);
FORCEPROP 2 LASTPIN (-4175 1750) $PN CP73
J 2
(-4185 1760);
DISPLAY 0.617021 (-4185 1760);
PAINT ORANGE (-4185 1760);
FORCEPROP 2 LASTPIN (-4175 1700) $PN CP75
J 2
(-4185 1710);
DISPLAY 0.617021 (-4185 1710);
PAINT ORANGE (-4185 1710);
FORCEPROP 2 LASTPIN (-4175 1650) $PN CP81
J 2
(-4185 1660);
DISPLAY 0.617021 (-4185 1660);
PAINT ORANGE (-4185 1660);
FORCEPROP 2 LASTPIN (-4175 1600) $PN CP83
J 2
(-4185 1610);
DISPLAY 0.617021 (-4185 1610);
PAINT ORANGE (-4185 1610);
FORCEPROP 2 LASTPIN (-4175 1550) $PN CR6
J 2
(-4185 1560);
DISPLAY 0.617021 (-4185 1560);
PAINT ORANGE (-4185 1560);
FORCEPROP 2 LASTPIN (-4175 1500) $PN CR10
J 2
(-4185 1510);
DISPLAY 0.617021 (-4185 1510);
PAINT ORANGE (-4185 1510);
FORCEPROP 2 LASTPIN (-4175 1450) $PN CR22
J 2
(-4185 1460);
DISPLAY 0.617021 (-4185 1460);
PAINT ORANGE (-4185 1460);
FORCEPROP 2 LASTPIN (-4175 1400) $PN CR24
J 2
(-4185 1410);
DISPLAY 0.617021 (-4185 1410);
PAINT ORANGE (-4185 1410);
FORCEPROP 2 LASTPIN (-4175 1350) $PN CR32
J 2
(-4185 1360);
DISPLAY 0.617021 (-4185 1360);
PAINT ORANGE (-4185 1360);
FORCEPROP 2 LASTPIN (-4175 1300) $PN CR58
J 2
(-4185 1310);
DISPLAY 0.617021 (-4185 1310);
PAINT ORANGE (-4185 1310);
FORCEPROP 2 LASTPIN (-4175 1250) $PN CR62
J 2
(-4185 1260);
DISPLAY 0.617021 (-4185 1260);
PAINT ORANGE (-4185 1260);
FORCEPROP 2 LASTPIN (-4175 1200) $PN CR64
J 2
(-4185 1210);
DISPLAY 0.617021 (-4185 1210);
PAINT ORANGE (-4185 1210);
FORCEPROP 2 LASTPIN (-4175 1150) $PN CR66
J 2
(-4185 1160);
DISPLAY 0.617021 (-4185 1160);
PAINT ORANGE (-4185 1160);
FORCEPROP 2 LASTPIN (-4175 1100) $PN CR68
J 2
(-4185 1110);
DISPLAY 0.617021 (-4185 1110);
PAINT ORANGE (-4185 1110);
FORCEPROP 2 LASTPIN (-4175 1050) $PN CR78
J 2
(-4185 1060);
DISPLAY 0.617021 (-4185 1060);
PAINT ORANGE (-4185 1060);
FORCEPROP 2 LASTPIN (-4175 1000) $PN CR86
J 2
(-4185 1010);
DISPLAY 0.617021 (-4185 1010);
PAINT ORANGE (-4185 1010);
FORCEPROP 2 LASTPIN (-4175 950) $PN H57
J 2
(-4185 960);
DISPLAY 0.617021 (-4185 960);
PAINT ORANGE (-4185 960);
FORCEPROP 2 LASTPIN (-4175 900) $PN CT13
J 2
(-4185 910);
DISPLAY 0.617021 (-4185 910);
PAINT ORANGE (-4185 910);
FORCEPROP 2 LASTPIN (-4175 850) $PN CT19
J 2
(-4185 860);
DISPLAY 0.617021 (-4185 860);
PAINT ORANGE (-4185 860);
FORCEPROP 2 LASTPIN (-4175 800) $PN CT27
J 2
(-4185 810);
DISPLAY 0.617021 (-4185 810);
PAINT ORANGE (-4185 810);
FORCEPROP 2 LASTPIN (-4175 750) $PN CT29
J 2
(-4185 760);
DISPLAY 0.617021 (-4185 760);
PAINT ORANGE (-4185 760);
FORCEPROP 2 LASTPIN (-4175 700) $PN CT33
J 2
(-4185 710);
DISPLAY 0.617021 (-4185 710);
PAINT ORANGE (-4185 710);
FORCEPROP 2 LASTPIN (-2975 4650) $PN CT35
J 0
(-2965 4660);
DISPLAY 0.617021 (-2965 4660);
PAINT ORANGE (-2965 4660);
FORCEPROP 2 LASTPIN (-2975 4600) $PN CT57
J 0
(-2965 4610);
DISPLAY 0.617021 (-2965 4610);
PAINT ORANGE (-2965 4610);
FORCEPROP 2 LASTPIN (-2975 4550) $PN CT73
J 0
(-2965 4560);
DISPLAY 0.617021 (-2965 4560);
PAINT ORANGE (-2965 4560);
FORCEPROP 2 LASTPIN (-2975 4500) $PN CT79
J 0
(-2965 4510);
DISPLAY 0.617021 (-2965 4510);
PAINT ORANGE (-2965 4510);
FORCEPROP 2 LASTPIN (-2975 4450) $PN CT83
J 0
(-2965 4460);
DISPLAY 0.617021 (-2965 4460);
PAINT ORANGE (-2965 4460);
FORCEPROP 2 LASTPIN (-2975 4400) $PN CT85
J 0
(-2965 4410);
DISPLAY 0.617021 (-2965 4410);
PAINT ORANGE (-2965 4410);
FORCEPROP 2 LASTPIN (-2975 4350) $PN CU4
J 0
(-2965 4360);
DISPLAY 0.617021 (-2965 4360);
PAINT ORANGE (-2965 4360);
FORCEPROP 2 LASTPIN (-2975 4300) $PN CU22
J 0
(-2965 4310);
DISPLAY 0.617021 (-2965 4310);
PAINT ORANGE (-2965 4310);
FORCEPROP 2 LASTPIN (-2975 4250) $PN CU28
J 0
(-2965 4260);
DISPLAY 0.617021 (-2965 4260);
PAINT ORANGE (-2965 4260);
FORCEPROP 2 LASTPIN (-2975 4200) $PN CU30
J 0
(-2965 4210);
DISPLAY 0.617021 (-2965 4210);
PAINT ORANGE (-2965 4210);
FORCEPROP 2 LASTPIN (-2975 4150) $PN CU34
J 0
(-2965 4160);
DISPLAY 0.617021 (-2965 4160);
PAINT ORANGE (-2965 4160);
FORCEPROP 2 LASTPIN (-2975 4100) $PN CU36
J 0
(-2965 4110);
DISPLAY 0.617021 (-2965 4110);
PAINT ORANGE (-2965 4110);
FORCEPROP 2 LASTPIN (-2975 4050) $PN CU56
J 0
(-2965 4060);
DISPLAY 0.617021 (-2965 4060);
PAINT ORANGE (-2965 4060);
FORCEPROP 2 LASTPIN (-2975 4000) $PN CU62
J 0
(-2965 4010);
DISPLAY 0.617021 (-2965 4010);
PAINT ORANGE (-2965 4010);
FORCEPROP 2 LASTPIN (-2975 3950) $PN CU68
J 0
(-2965 3960);
DISPLAY 0.617021 (-2965 3960);
PAINT ORANGE (-2965 3960);
FORCEPROP 2 LASTPIN (-2975 3900) $PN CU76
J 0
(-2965 3910);
DISPLAY 0.617021 (-2965 3910);
PAINT ORANGE (-2965 3910);
FORCEPROP 2 LASTPIN (-2975 3850) $PN CU78
J 0
(-2965 3860);
DISPLAY 0.617021 (-2965 3860);
PAINT ORANGE (-2965 3860);
FORCEPROP 2 LASTPIN (-2975 3800) $PN CU80
J 0
(-2965 3810);
DISPLAY 0.617021 (-2965 3810);
PAINT ORANGE (-2965 3810);
FORCEPROP 2 LASTPIN (-2975 3750) $PN CU82
J 0
(-2965 3760);
DISPLAY 0.617021 (-2965 3760);
PAINT ORANGE (-2965 3760);
FORCEPROP 2 LASTPIN (-2975 3700) $PN CU86
J 0
(-2965 3710);
DISPLAY 0.617021 (-2965 3710);
PAINT ORANGE (-2965 3710);
FORCEPROP 2 LASTPIN (-2975 3650) $PN CV1
J 0
(-2965 3660);
DISPLAY 0.617021 (-2965 3660);
PAINT ORANGE (-2965 3660);
FORCEPROP 2 LASTPIN (-2975 3600) $PN H55
J 0
(-2965 3610);
DISPLAY 0.617021 (-2965 3610);
PAINT ORANGE (-2965 3610);
FORCEPROP 2 LASTPIN (-2975 3550) $PN CV17
J 0
(-2965 3560);
DISPLAY 0.617021 (-2965 3560);
PAINT ORANGE (-2965 3560);
FORCEPROP 2 LASTPIN (-2975 3500) $PN CV25
J 0
(-2965 3510);
DISPLAY 0.617021 (-2965 3510);
PAINT ORANGE (-2965 3510);
FORCEPROP 2 LASTPIN (-2975 3450) $PN CV27
J 0
(-2965 3460);
DISPLAY 0.617021 (-2965 3460);
PAINT ORANGE (-2965 3460);
FORCEPROP 2 LASTPIN (-2975 3400) $PN CV31
J 0
(-2965 3410);
DISPLAY 0.617021 (-2965 3410);
PAINT ORANGE (-2965 3410);
FORCEPROP 2 LASTPIN (-2975 3350) $PN CV33
J 0
(-2965 3360);
DISPLAY 0.617021 (-2965 3360);
PAINT ORANGE (-2965 3360);
FORCEPROP 2 LASTPIN (-2975 3300) $PN CV37
J 0
(-2965 3310);
DISPLAY 0.617021 (-2965 3310);
PAINT ORANGE (-2965 3310);
FORCEPROP 2 LASTPIN (-2975 3250) $PN CV39
J 0
(-2965 3260);
DISPLAY 0.617021 (-2965 3260);
PAINT ORANGE (-2965 3260);
FORCEPROP 2 LASTPIN (-2975 3200) $PN CV41
J 0
(-2965 3210);
DISPLAY 0.617021 (-2965 3210);
PAINT ORANGE (-2965 3210);
FORCEPROP 2 LASTPIN (-2975 3150) $PN CV53
J 0
(-2965 3160);
DISPLAY 0.617021 (-2965 3160);
PAINT ORANGE (-2965 3160);
FORCEPROP 2 LASTPIN (-2975 3100) $PN CV55
J 0
(-2965 3110);
DISPLAY 0.617021 (-2965 3110);
PAINT ORANGE (-2965 3110);
FORCEPROP 2 LASTPIN (-2975 3050) $PN CV63
J 0
(-2965 3060);
DISPLAY 0.617021 (-2965 3060);
PAINT ORANGE (-2965 3060);
FORCEPROP 2 LASTPIN (-2975 3000) $PN CV67
J 0
(-2965 3010);
DISPLAY 0.617021 (-2965 3010);
PAINT ORANGE (-2965 3010);
FORCEPROP 2 LASTPIN (-2975 2950) $PN CV73
J 0
(-2965 2960);
DISPLAY 0.617021 (-2965 2960);
PAINT ORANGE (-2965 2960);
FORCEPROP 2 LASTPIN (-2975 2900) $PN CV79
J 0
(-2965 2910);
DISPLAY 0.617021 (-2965 2910);
PAINT ORANGE (-2965 2910);
FORCEPROP 2 LASTPIN (-2975 2850) $PN CV81
J 0
(-2965 2860);
DISPLAY 0.617021 (-2965 2860);
PAINT ORANGE (-2965 2860);
FORCEPROP 2 LASTPIN (-2975 2800) $PN CV83
J 0
(-2965 2810);
DISPLAY 0.617021 (-2965 2810);
PAINT ORANGE (-2965 2810);
FORCEPROP 2 LASTPIN (-2975 2750) $PN CW12
J 0
(-2965 2760);
DISPLAY 0.617021 (-2965 2760);
PAINT ORANGE (-2965 2760);
FORCEPROP 2 LASTPIN (-2975 2700) $PN CW26
J 0
(-2965 2710);
DISPLAY 0.617021 (-2965 2710);
PAINT ORANGE (-2965 2710);
FORCEPROP 2 LASTPIN (-2975 2650) $PN CW32
J 0
(-2965 2660);
DISPLAY 0.617021 (-2965 2660);
PAINT ORANGE (-2965 2660);
FORCEPROP 2 LASTPIN (-2975 2600) $PN CW38
J 0
(-2965 2610);
DISPLAY 0.617021 (-2965 2610);
PAINT ORANGE (-2965 2610);
FORCEPROP 2 LASTPIN (-2975 2550) $PN CW40
J 0
(-2965 2560);
DISPLAY 0.617021 (-2965 2560);
PAINT ORANGE (-2965 2560);
FORCEPROP 2 LASTPIN (-2975 2500) $PN CW42
J 0
(-2965 2510);
DISPLAY 0.617021 (-2965 2510);
PAINT ORANGE (-2965 2510);
FORCEPROP 2 LASTPIN (-2975 2450) $PN CW52
J 0
(-2965 2460);
DISPLAY 0.617021 (-2965 2460);
PAINT ORANGE (-2965 2460);
FORCEPROP 2 LASTPIN (-2975 2400) $PN CW54
J 0
(-2965 2410);
DISPLAY 0.617021 (-2965 2410);
PAINT ORANGE (-2965 2410);
FORCEPROP 2 LASTPIN (-2975 2350) $PN CW64
J 0
(-2965 2360);
DISPLAY 0.617021 (-2965 2360);
PAINT ORANGE (-2965 2360);
FORCEPROP 2 LASTPIN (-2975 2300) $PN CW66
J 0
(-2965 2310);
DISPLAY 0.617021 (-2965 2310);
PAINT ORANGE (-2965 2310);
FORCEPROP 2 LASTPIN (-2975 2250) $PN CW68
J 0
(-2965 2260);
DISPLAY 0.617021 (-2965 2260);
PAINT ORANGE (-2965 2260);
FORCEPROP 2 LASTPIN (-2975 2200) $PN CW74
J 0
(-2965 2210);
DISPLAY 0.617021 (-2965 2210);
PAINT ORANGE (-2965 2210);
FORCEPROP 2 LASTPIN (-2975 2150) $PN CW78
J 0
(-2965 2160);
DISPLAY 0.617021 (-2965 2160);
PAINT ORANGE (-2965 2160);
FORCEPROP 2 LASTPIN (-2975 2100) $PN CW82
J 0
(-2965 2110);
DISPLAY 0.617021 (-2965 2110);
PAINT ORANGE (-2965 2110);
FORCEPROP 2 LASTPIN (-2975 2050) $PN CY1
J 0
(-2965 2060);
DISPLAY 0.617021 (-2965 2060);
PAINT ORANGE (-2965 2060);
FORCEPROP 2 LASTPIN (-2975 2000) $PN CY9
J 0
(-2965 2010);
DISPLAY 0.617021 (-2965 2010);
PAINT ORANGE (-2965 2010);
FORCEPROP 2 LASTPIN (-2975 1950) $PN CY13
J 0
(-2965 1960);
DISPLAY 0.617021 (-2965 1960);
PAINT ORANGE (-2965 1960);
FORCEPROP 2 LASTPIN (-2975 1900) $PN CY15
J 0
(-2965 1910);
DISPLAY 0.617021 (-2965 1910);
PAINT ORANGE (-2965 1910);
FORCEPROP 2 LASTPIN (-2975 1850) $PN CY21
J 0
(-2965 1860);
DISPLAY 0.617021 (-2965 1860);
PAINT ORANGE (-2965 1860);
FORCEPROP 2 LASTPIN (-2975 1800) $PN CY41
J 0
(-2965 1810);
DISPLAY 0.617021 (-2965 1810);
PAINT ORANGE (-2965 1810);
FORCEPROP 2 LASTPIN (-2975 1750) $PN CY45
J 0
(-2965 1760);
DISPLAY 0.617021 (-2965 1760);
PAINT ORANGE (-2965 1760);
FORCEPROP 2 LASTPIN (-2975 1700) $PN CY51
J 0
(-2965 1710);
DISPLAY 0.617021 (-2965 1710);
PAINT ORANGE (-2965 1710);
FORCEPROP 2 LASTPIN (-2975 1650) $PN CY59
J 0
(-2965 1660);
DISPLAY 0.617021 (-2965 1660);
PAINT ORANGE (-2965 1660);
FORCEPROP 2 LASTPIN (-2975 1600) $PN CY61
J 0
(-2965 1610);
DISPLAY 0.617021 (-2965 1610);
PAINT ORANGE (-2965 1610);
FORCEPROP 2 LASTPIN (-2975 1550) $PN CY65
J 0
(-2965 1560);
DISPLAY 0.617021 (-2965 1560);
PAINT ORANGE (-2965 1560);
FORCEPROP 2 LASTPIN (-2975 1500) $PN CY69
J 0
(-2965 1510);
DISPLAY 0.617021 (-2965 1510);
PAINT ORANGE (-2965 1510);
FORCEPROP 2 LASTPIN (-2975 1450) $PN CY75
J 0
(-2965 1460);
DISPLAY 0.617021 (-2965 1460);
PAINT ORANGE (-2965 1460);
FORCEPROP 2 LASTPIN (-2975 1400) $PN CY77
J 0
(-2965 1410);
DISPLAY 0.617021 (-2965 1410);
PAINT ORANGE (-2965 1410);
FORCEPROP 2 LASTPIN (-2975 1350) $PN CY83
J 0
(-2965 1360);
DISPLAY 0.617021 (-2965 1360);
PAINT ORANGE (-2965 1360);
FORCEPROP 2 LASTPIN (-2975 1300) $PN CY85
J 0
(-2965 1310);
DISPLAY 0.617021 (-2965 1310);
PAINT ORANGE (-2965 1310);
FORCEPROP 2 LASTPIN (-2975 1250) $PN DA6
J 0
(-2965 1260);
DISPLAY 0.617021 (-2965 1260);
PAINT ORANGE (-2965 1260);
FORCEPROP 2 LASTPIN (-2975 1200) $PN H53
J 0
(-2965 1210);
DISPLAY 0.617021 (-2965 1210);
PAINT ORANGE (-2965 1210);
FORCEPROP 2 LASTPIN (-2975 1150) $PN DA18
J 0
(-2965 1160);
DISPLAY 0.617021 (-2965 1160);
PAINT ORANGE (-2965 1160);
FORCEPROP 2 LASTPIN (-2975 1100) $PN DA26
J 0
(-2965 1110);
DISPLAY 0.617021 (-2965 1110);
PAINT ORANGE (-2965 1110);
FORCEPROP 2 LASTPIN (-2975 1050) $PN DA28
J 0
(-2965 1060);
DISPLAY 0.617021 (-2965 1060);
PAINT ORANGE (-2965 1060);
FORCEPROP 2 LASTPIN (-2975 1000) $PN DA30
J 0
(-2965 1010);
DISPLAY 0.617021 (-2965 1010);
PAINT ORANGE (-2965 1010);
FORCEPROP 2 LASTPIN (-2975 950) $PN DA32
J 0
(-2965 960);
DISPLAY 0.617021 (-2965 960);
PAINT ORANGE (-2965 960);
FORCEPROP 2 LASTPIN (-2975 900) $PN DA34
J 0
(-2965 910);
DISPLAY 0.617021 (-2965 910);
PAINT ORANGE (-2965 910);
FORCEPROP 2 LASTPIN (-2975 850) $PN DA36
J 0
(-2965 860);
DISPLAY 0.617021 (-2965 860);
PAINT ORANGE (-2965 860);
FORCEPROP 2 LASTPIN (-2975 800) $PN DA38
J 0
(-2965 810);
DISPLAY 0.617021 (-2965 810);
PAINT ORANGE (-2965 810);
FORCEPROP 2 LASTPIN (-2975 750) $PN DA44
J 0
(-2965 760);
DISPLAY 0.617021 (-2965 760);
PAINT ORANGE (-2965 760);
FORCEPROP 2 LASTPIN (-2975 700) $PN DA46
J 0
(-2965 710);
DISPLAY 0.617021 (-2965 710);
PAINT ORANGE (-2965 710);
FORCEPROP 1 LAST PACK_TYPE BGA1
J 0
(-4125 4950);
PAINT SKYBLUE (-4125 4950);
DISPLAY INVISIBLE (-4125 4950);
FORCEPROP 2 LAST CDS_LIB chpset_lib
J 0
(-3575 2650);
PAINT ORANGE (-3575 2650);
DISPLAY INVISIBLE (-3575 2650);
FORCEPROP 2 LAST SEC_TYPE BGA1
J 0
(-4125 4950);
DISPLAY 1.021277 (-4125 4950);
PAINT ORANGE (-4125 4950);
DISPLAY INVISIBLE (-4125 4950);
FORCEPROP 2 LAST SEC 28
J 0
(-4125 4950);
DISPLAY 0.680851 (-4125 4950);
PAINT MONO (-4125 4950);
DISPLAY INVISIBLE (-4125 4950);
FORCEPROP 2 LAST CDS_LOCATION U5D1
J 0
(-4125 4900);
DISPLAY 0.617021 (-4125 4900);
PAINT AQUA (-4125 4900);
DISPLAY INVISIBLE (-4125 4900);
FORCEPROP 1 LAST PATH I284
J 0
(-3575 4850);
PAINT GREEN (-3575 4850);
DISPLAY INVISIBLE (-3575 4850);
FORCEPROP 0 LAST ROOM CPU0
J 0
(-4125 5000);
DISPLAY 1.021277 (-4125 5000);
PAINT ORANGE (-4125 5000);
DISPLAY INVISIBLE (-4125 5000);
FORCEADD SKX_EXT_B..29
(-1850 2600);
FORCEPROP 1 LAST LOCATION U5D1
J 0
(-2400 4850);
DISPLAY 0.617021 (-2400 4850);
PAINT AQUA (-2400 4850);
FORCEPROP 1 LAST PART_NUMBER TBD
J 0
(-2400 450);
DISPLAY 0.617021 (-2400 450);
PAINT BLUE (-2400 450);
FORCEPROP 1 LAST MATERIAL IC
J 0
(-2400 4800);
DISPLAY 0.617021 (-2400 4800);
PAINT SKYBLUE (-2400 4800);
FORCEPROP 2 LASTPIN (-2450 4600) $PN DA48
J 2
(-2460 4610);
DISPLAY 0.617021 (-2460 4610);
PAINT ORANGE (-2460 4610);
FORCEPROP 2 LASTPIN (-2450 4550) $PN DA50
J 2
(-2460 4560);
DISPLAY 0.617021 (-2460 4560);
PAINT ORANGE (-2460 4560);
FORCEPROP 2 LASTPIN (-2450 4500) $PN DA64
J 2
(-2460 4510);
DISPLAY 0.617021 (-2460 4510);
PAINT ORANGE (-2460 4510);
FORCEPROP 2 LASTPIN (-2450 4450) $PN DA70
J 2
(-2460 4460);
DISPLAY 0.617021 (-2460 4460);
PAINT ORANGE (-2460 4460);
FORCEPROP 2 LASTPIN (-2450 4400) $PN DA74
J 2
(-2460 4410);
DISPLAY 0.617021 (-2460 4410);
PAINT ORANGE (-2460 4410);
FORCEPROP 2 LASTPIN (-2450 4350) $PN DA76
J 2
(-2460 4360);
DISPLAY 0.617021 (-2460 4360);
PAINT ORANGE (-2460 4360);
FORCEPROP 2 LASTPIN (-2450 4300) $PN DA78
J 2
(-2460 4310);
DISPLAY 0.617021 (-2460 4310);
PAINT ORANGE (-2460 4310);
FORCEPROP 2 LASTPIN (-2450 4250) $PN DA80
J 2
(-2460 4260);
DISPLAY 0.617021 (-2460 4260);
PAINT ORANGE (-2460 4260);
FORCEPROP 2 LASTPIN (-2450 4200) $PN DB3
J 2
(-2460 4210);
DISPLAY 0.617021 (-2460 4210);
PAINT ORANGE (-2460 4210);
FORCEPROP 2 LASTPIN (-2450 4150) $PN DB13
J 2
(-2460 4160);
DISPLAY 0.617021 (-2460 4160);
PAINT ORANGE (-2460 4160);
FORCEPROP 2 LASTPIN (-2450 4100) $PN DB17
J 2
(-2460 4110);
DISPLAY 0.617021 (-2460 4110);
PAINT ORANGE (-2460 4110);
FORCEPROP 2 LASTPIN (-2450 4050) $PN DB23
J 2
(-2460 4060);
DISPLAY 0.617021 (-2460 4060);
PAINT ORANGE (-2460 4060);
FORCEPROP 2 LASTPIN (-2450 4000) $PN DB25
J 2
(-2460 4010);
DISPLAY 0.617021 (-2460 4010);
PAINT ORANGE (-2460 4010);
FORCEPROP 2 LASTPIN (-2450 3950) $PN DB39
J 2
(-2460 3960);
DISPLAY 0.617021 (-2460 3960);
PAINT ORANGE (-2460 3960);
FORCEPROP 2 LASTPIN (-2450 3900) $PN DB41
J 2
(-2460 3910);
DISPLAY 0.617021 (-2460 3910);
PAINT ORANGE (-2460 3910);
FORCEPROP 2 LASTPIN (-2450 3850) $PN DB47
J 2
(-2460 3860);
DISPLAY 0.617021 (-2460 3860);
PAINT ORANGE (-2460 3860);
FORCEPROP 2 LASTPIN (-2450 3800) $PN DB49
J 2
(-2460 3810);
DISPLAY 0.617021 (-2460 3810);
PAINT ORANGE (-2460 3810);
FORCEPROP 2 LASTPIN (-2450 3750) $PN DB73
J 2
(-2460 3760);
DISPLAY 0.617021 (-2460 3760);
PAINT ORANGE (-2460 3760);
FORCEPROP 2 LASTPIN (-2450 3700) $PN DB77
J 2
(-2460 3710);
DISPLAY 0.617021 (-2460 3710);
PAINT ORANGE (-2460 3710);
FORCEPROP 2 LASTPIN (-2450 3650) $PN DB83
J 2
(-2460 3660);
DISPLAY 0.617021 (-2460 3660);
PAINT ORANGE (-2460 3660);
FORCEPROP 2 LASTPIN (-2450 3600) $PN DB85
J 2
(-2460 3610);
DISPLAY 0.617021 (-2460 3610);
PAINT ORANGE (-2460 3610);
FORCEPROP 2 LASTPIN (-2450 3550) $PN DC14
J 2
(-2460 3560);
DISPLAY 0.617021 (-2460 3560);
PAINT ORANGE (-2460 3560);
FORCEPROP 2 LASTPIN (-2450 3500) $PN DC24
J 2
(-2460 3510);
DISPLAY 0.617021 (-2460 3510);
PAINT ORANGE (-2460 3510);
FORCEPROP 2 LASTPIN (-2450 3450) $PN DC26
J 2
(-2460 3460);
DISPLAY 0.617021 (-2460 3460);
PAINT ORANGE (-2460 3460);
FORCEPROP 2 LASTPIN (-2450 3400) $PN DC32
J 2
(-2460 3410);
DISPLAY 0.617021 (-2460 3410);
PAINT ORANGE (-2460 3410);
FORCEPROP 2 LASTPIN (-2450 3350) $PN DC38
J 2
(-2460 3360);
DISPLAY 0.617021 (-2460 3360);
PAINT ORANGE (-2460 3360);
FORCEPROP 2 LASTPIN (-2450 3300) $PN DC42
J 2
(-2460 3310);
DISPLAY 0.617021 (-2460 3310);
PAINT ORANGE (-2460 3310);
FORCEPROP 2 LASTPIN (-2450 3250) $PN DC64
J 2
(-2460 3260);
DISPLAY 0.617021 (-2460 3260);
PAINT ORANGE (-2460 3260);
FORCEPROP 2 LASTPIN (-2450 3200) $PN DC66
J 2
(-2460 3210);
DISPLAY 0.617021 (-2460 3210);
PAINT ORANGE (-2460 3210);
FORCEPROP 2 LASTPIN (-2450 3150) $PN DC68
J 2
(-2460 3160);
DISPLAY 0.617021 (-2460 3160);
PAINT ORANGE (-2460 3160);
FORCEPROP 2 LASTPIN (-2450 3100) $PN DC70
J 2
(-2460 3110);
DISPLAY 0.617021 (-2460 3110);
PAINT ORANGE (-2460 3110);
FORCEPROP 2 LASTPIN (-2450 3050) $PN DC78
J 2
(-2460 3060);
DISPLAY 0.617021 (-2460 3060);
PAINT ORANGE (-2460 3060);
FORCEPROP 2 LASTPIN (-2450 3000) $PN DC84
J 2
(-2460 3010);
DISPLAY 0.617021 (-2460 3010);
PAINT ORANGE (-2460 3010);
FORCEPROP 2 LASTPIN (-2450 2950) $PN DC86
J 2
(-2460 2960);
DISPLAY 0.617021 (-2460 2960);
PAINT ORANGE (-2460 2960);
FORCEPROP 2 LASTPIN (-2450 2900) $PN DD11
J 2
(-2460 2910);
DISPLAY 0.617021 (-2460 2910);
PAINT ORANGE (-2460 2910);
FORCEPROP 2 LASTPIN (-2450 2850) $PN DD23
J 2
(-2460 2860);
DISPLAY 0.617021 (-2460 2860);
PAINT ORANGE (-2460 2860);
FORCEPROP 2 LASTPIN (-2450 2800) $PN DD27
J 2
(-2460 2810);
DISPLAY 0.617021 (-2460 2810);
PAINT ORANGE (-2460 2810);
FORCEPROP 2 LASTPIN (-2450 2750) $PN DD31
J 2
(-2460 2760);
DISPLAY 0.617021 (-2460 2760);
PAINT ORANGE (-2460 2760);
FORCEPROP 2 LASTPIN (-2450 2700) $PN DD33
J 2
(-2460 2710);
DISPLAY 0.617021 (-2460 2710);
PAINT ORANGE (-2460 2710);
FORCEPROP 2 LASTPIN (-2450 2650) $PN DD37
J 2
(-2460 2660);
DISPLAY 0.617021 (-2460 2660);
PAINT ORANGE (-2460 2660);
FORCEPROP 2 LASTPIN (-2450 2600) $PN DD71
J 2
(-2460 2610);
DISPLAY 0.617021 (-2460 2610);
PAINT ORANGE (-2460 2610);
FORCEPROP 2 LASTPIN (-2450 2550) $PN DD73
J 2
(-2460 2560);
DISPLAY 0.617021 (-2460 2560);
PAINT ORANGE (-2460 2560);
FORCEPROP 2 LASTPIN (-2450 2500) $PN DD75
J 2
(-2460 2510);
DISPLAY 0.617021 (-2460 2510);
PAINT ORANGE (-2460 2510);
FORCEPROP 2 LASTPIN (-2450 2450) $PN DD81
J 2
(-2460 2460);
DISPLAY 0.617021 (-2460 2460);
PAINT ORANGE (-2460 2460);
FORCEPROP 2 LASTPIN (-2450 2400) $PN DD83
J 2
(-2460 2410);
DISPLAY 0.617021 (-2460 2410);
PAINT ORANGE (-2460 2410);
FORCEPROP 2 LASTPIN (-2450 2350) $PN DE6
J 2
(-2460 2360);
DISPLAY 0.617021 (-2460 2360);
PAINT ORANGE (-2460 2360);
FORCEPROP 2 LASTPIN (-2450 2300) $PN DE8
J 2
(-2460 2310);
DISPLAY 0.617021 (-2460 2310);
PAINT ORANGE (-2460 2310);
FORCEPROP 2 LASTPIN (-2450 2250) $PN DE18
J 2
(-2460 2260);
DISPLAY 0.617021 (-2460 2260);
PAINT ORANGE (-2460 2260);
FORCEPROP 2 LASTPIN (-2450 2200) $PN DE20
J 2
(-2460 2210);
DISPLAY 0.617021 (-2460 2210);
PAINT ORANGE (-2460 2210);
FORCEPROP 2 LASTPIN (-2450 2150) $PN DE24
J 2
(-2460 2160);
DISPLAY 0.617021 (-2460 2160);
PAINT ORANGE (-2460 2160);
FORCEPROP 2 LASTPIN (-2450 2100) $PN DE28
J 2
(-2460 2110);
DISPLAY 0.617021 (-2460 2110);
PAINT ORANGE (-2460 2110);
FORCEPROP 2 LASTPIN (-2450 2050) $PN DE30
J 2
(-2460 2060);
DISPLAY 0.617021 (-2460 2060);
PAINT ORANGE (-2460 2060);
FORCEPROP 2 LASTPIN (-2450 2000) $PN DE34
J 2
(-2460 2010);
DISPLAY 0.617021 (-2460 2010);
PAINT ORANGE (-2460 2010);
FORCEPROP 2 LASTPIN (-2450 1950) $PN DE36
J 2
(-2460 1960);
DISPLAY 0.617021 (-2460 1960);
PAINT ORANGE (-2460 1960);
FORCEPROP 2 LASTPIN (-2450 1900) $PN DE64
J 2
(-2460 1910);
DISPLAY 0.617021 (-2460 1910);
PAINT ORANGE (-2460 1910);
FORCEPROP 2 LASTPIN (-2450 1850) $PN DE70
J 2
(-2460 1860);
DISPLAY 0.617021 (-2460 1860);
PAINT ORANGE (-2460 1860);
FORCEPROP 2 LASTPIN (-2450 1800) $PN DE72
J 2
(-2460 1810);
DISPLAY 0.617021 (-2460 1810);
PAINT ORANGE (-2460 1810);
FORCEPROP 2 LASTPIN (-2450 1750) $PN DE78
J 2
(-2460 1760);
DISPLAY 0.617021 (-2460 1760);
PAINT ORANGE (-2460 1760);
FORCEPROP 2 LASTPIN (-2450 1700) $PN DF5
J 2
(-2460 1710);
DISPLAY 0.617021 (-2460 1710);
PAINT ORANGE (-2460 1710);
FORCEPROP 2 LASTPIN (-2450 1650) $PN DF7
J 2
(-2460 1660);
DISPLAY 0.617021 (-2460 1660);
PAINT ORANGE (-2460 1660);
FORCEPROP 2 LASTPIN (-2450 1600) $PN H51
J 2
(-2460 1610);
DISPLAY 0.617021 (-2460 1610);
PAINT ORANGE (-2460 1610);
FORCEPROP 2 LASTPIN (-2450 1550) $PN DF19
J 2
(-2460 1560);
DISPLAY 0.617021 (-2460 1560);
PAINT ORANGE (-2460 1560);
FORCEPROP 2 LASTPIN (-2450 1500) $PN DF29
J 2
(-2460 1510);
DISPLAY 0.617021 (-2460 1510);
PAINT ORANGE (-2460 1510);
FORCEPROP 2 LASTPIN (-2450 1450) $PN DF35
J 2
(-2460 1460);
DISPLAY 0.617021 (-2460 1460);
PAINT ORANGE (-2460 1460);
FORCEPROP 2 LASTPIN (-2450 1400) $PN DF37
J 2
(-2460 1410);
DISPLAY 0.617021 (-2460 1410);
PAINT ORANGE (-2460 1410);
FORCEPROP 2 LASTPIN (-2450 1350) $PN DF39
J 2
(-2460 1360);
DISPLAY 0.617021 (-2460 1360);
PAINT ORANGE (-2460 1360);
FORCEPROP 2 LASTPIN (-2450 1300) $PN DF41
J 2
(-2460 1310);
DISPLAY 0.617021 (-2460 1310);
PAINT ORANGE (-2460 1310);
FORCEPROP 2 LASTPIN (-2450 1250) $PN DF65
J 2
(-2460 1260);
DISPLAY 0.617021 (-2460 1260);
PAINT ORANGE (-2460 1260);
FORCEPROP 2 LASTPIN (-2450 1200) $PN DF69
J 2
(-2460 1210);
DISPLAY 0.617021 (-2460 1210);
PAINT ORANGE (-2460 1210);
FORCEPROP 2 LASTPIN (-2450 1150) $PN DF73
J 2
(-2460 1160);
DISPLAY 0.617021 (-2460 1160);
PAINT ORANGE (-2460 1160);
FORCEPROP 2 LASTPIN (-2450 1100) $PN DF79
J 2
(-2460 1110);
DISPLAY 0.617021 (-2460 1110);
PAINT ORANGE (-2460 1110);
FORCEPROP 2 LASTPIN (-2450 1050) $PN DF83
J 2
(-2460 1060);
DISPLAY 0.617021 (-2460 1060);
PAINT ORANGE (-2460 1060);
FORCEPROP 2 LASTPIN (-2450 1000) $PN DF85
J 2
(-2460 1010);
DISPLAY 0.617021 (-2460 1010);
PAINT ORANGE (-2460 1010);
FORCEPROP 2 LASTPIN (-2450 950) $PN DG2
J 2
(-2460 960);
DISPLAY 0.617021 (-2460 960);
PAINT ORANGE (-2460 960);
FORCEPROP 2 LASTPIN (-2450 900) $PN H49
J 2
(-2460 910);
DISPLAY 0.617021 (-2460 910);
PAINT ORANGE (-2460 910);
FORCEPROP 2 LASTPIN (-2450 850) $PN DG14
J 2
(-2460 860);
DISPLAY 0.617021 (-2460 860);
PAINT ORANGE (-2460 860);
FORCEPROP 2 LASTPIN (-2450 800) $PN DG16
J 2
(-2460 810);
DISPLAY 0.617021 (-2460 810);
PAINT ORANGE (-2460 810);
FORCEPROP 2 LASTPIN (-2450 750) $PN DG24
J 2
(-2460 760);
DISPLAY 0.617021 (-2460 760);
PAINT ORANGE (-2460 760);
FORCEPROP 2 LASTPIN (-2450 700) $PN DG66
J 2
(-2460 710);
DISPLAY 0.617021 (-2460 710);
PAINT ORANGE (-2460 710);
FORCEPROP 2 LASTPIN (-2450 650) $PN DG68
J 2
(-2460 660);
DISPLAY 0.617021 (-2460 660);
PAINT ORANGE (-2460 660);
FORCEPROP 2 LASTPIN (-1250 4600) $PN DG76
J 0
(-1240 4610);
DISPLAY 0.617021 (-1240 4610);
PAINT ORANGE (-1240 4610);
FORCEPROP 2 LASTPIN (-1250 4550) $PN DG78
J 0
(-1240 4560);
DISPLAY 0.617021 (-1240 4560);
PAINT ORANGE (-1240 4560);
FORCEPROP 2 LASTPIN (-1250 4500) $PN DG80
J 0
(-1240 4510);
DISPLAY 0.617021 (-1240 4510);
PAINT ORANGE (-1240 4510);
FORCEPROP 2 LASTPIN (-1250 4450) $PN DG82
J 0
(-1240 4460);
DISPLAY 0.617021 (-1240 4460);
PAINT ORANGE (-1240 4460);
FORCEPROP 2 LASTPIN (-1250 4400) $PN DH13
J 0
(-1240 4410);
DISPLAY 0.617021 (-1240 4410);
PAINT ORANGE (-1240 4410);
FORCEPROP 2 LASTPIN (-1250 4350) $PN DH15
J 0
(-1240 4360);
DISPLAY 0.617021 (-1240 4360);
PAINT ORANGE (-1240 4360);
FORCEPROP 2 LASTPIN (-1250 4300) $PN DH23
J 0
(-1240 4310);
DISPLAY 0.617021 (-1240 4310);
PAINT ORANGE (-1240 4310);
FORCEPROP 2 LASTPIN (-1250 4250) $PN DH25
J 0
(-1240 4260);
DISPLAY 0.617021 (-1240 4260);
PAINT ORANGE (-1240 4260);
FORCEPROP 2 LASTPIN (-1250 4200) $PN DH27
J 0
(-1240 4210);
DISPLAY 0.617021 (-1240 4210);
PAINT ORANGE (-1240 4210);
FORCEPROP 2 LASTPIN (-1250 4150) $PN DH29
J 0
(-1240 4160);
DISPLAY 0.617021 (-1240 4160);
PAINT ORANGE (-1240 4160);
FORCEPROP 2 LASTPIN (-1250 4100) $PN DH31
J 0
(-1240 4110);
DISPLAY 0.617021 (-1240 4110);
PAINT ORANGE (-1240 4110);
FORCEPROP 2 LASTPIN (-1250 4050) $PN DH33
J 0
(-1240 4060);
DISPLAY 0.617021 (-1240 4060);
PAINT ORANGE (-1240 4060);
FORCEPROP 2 LASTPIN (-1250 4000) $PN DH35
J 0
(-1240 4010);
DISPLAY 0.617021 (-1240 4010);
PAINT ORANGE (-1240 4010);
FORCEPROP 2 LASTPIN (-1250 3950) $PN DH37
J 0
(-1240 3960);
DISPLAY 0.617021 (-1240 3960);
PAINT ORANGE (-1240 3960);
FORCEPROP 2 LASTPIN (-1250 3900) $PN DH41
J 0
(-1240 3910);
DISPLAY 0.617021 (-1240 3910);
PAINT ORANGE (-1240 3910);
FORCEPROP 2 LASTPIN (-1250 3850) $PN DH67
J 0
(-1240 3860);
DISPLAY 0.617021 (-1240 3860);
PAINT ORANGE (-1240 3860);
FORCEPROP 2 LASTPIN (-1250 3800) $PN DH71
J 0
(-1240 3810);
DISPLAY 0.617021 (-1240 3810);
PAINT ORANGE (-1240 3810);
FORCEPROP 2 LASTPIN (-1250 3750) $PN DH73
J 0
(-1240 3760);
DISPLAY 0.617021 (-1240 3760);
PAINT ORANGE (-1240 3760);
FORCEPROP 2 LASTPIN (-1250 3700) $PN DH79
J 0
(-1240 3710);
DISPLAY 0.617021 (-1240 3710);
PAINT ORANGE (-1240 3710);
FORCEPROP 2 LASTPIN (-1250 3650) $PN DH81
J 0
(-1240 3660);
DISPLAY 0.617021 (-1240 3660);
PAINT ORANGE (-1240 3660);
FORCEPROP 2 LASTPIN (-1250 3600) $PN DH83
J 0
(-1240 3610);
DISPLAY 0.617021 (-1240 3610);
PAINT ORANGE (-1240 3610);
FORCEPROP 2 LASTPIN (-1250 3550) $PN DJ2
J 0
(-1240 3560);
DISPLAY 0.617021 (-1240 3560);
PAINT ORANGE (-1240 3560);
FORCEPROP 2 LASTPIN (-1250 3500) $PN DJ10
J 0
(-1240 3510);
DISPLAY 0.617021 (-1240 3510);
PAINT ORANGE (-1240 3510);
FORCEPROP 2 LASTPIN (-1250 3450) $PN H47
J 0
(-1240 3460);
DISPLAY 0.617021 (-1240 3460);
PAINT ORANGE (-1240 3460);
FORCEPROP 2 LASTPIN (-1250 3400) $PN DJ22
J 0
(-1240 3410);
DISPLAY 0.617021 (-1240 3410);
PAINT ORANGE (-1240 3410);
FORCEPROP 2 LASTPIN (-1250 3350) $PN DJ38
J 0
(-1240 3360);
DISPLAY 0.617021 (-1240 3360);
PAINT ORANGE (-1240 3360);
FORCEPROP 2 LASTPIN (-1250 3300) $PN DJ42
J 0
(-1240 3310);
DISPLAY 0.617021 (-1240 3310);
PAINT ORANGE (-1240 3310);
FORCEPROP 2 LASTPIN (-1250 3250) $PN DJ68
J 0
(-1240 3260);
DISPLAY 0.617021 (-1240 3260);
PAINT ORANGE (-1240 3260);
FORCEPROP 2 LASTPIN (-1250 3200) $PN DJ74
J 0
(-1240 3210);
DISPLAY 0.617021 (-1240 3210);
PAINT ORANGE (-1240 3210);
FORCEPROP 2 LASTPIN (-1250 3150) $PN DJ78
J 0
(-1240 3160);
DISPLAY 0.617021 (-1240 3160);
PAINT ORANGE (-1240 3160);
FORCEPROP 2 LASTPIN (-1250 3100) $PN DJ82
J 0
(-1240 3110);
DISPLAY 0.617021 (-1240 3110);
PAINT ORANGE (-1240 3110);
FORCEPROP 2 LASTPIN (-1250 3050) $PN DJ84
J 0
(-1240 3060);
DISPLAY 0.617021 (-1240 3060);
PAINT ORANGE (-1240 3060);
FORCEPROP 2 LASTPIN (-1250 3000) $PN DK7
J 0
(-1240 3010);
DISPLAY 0.617021 (-1240 3010);
PAINT ORANGE (-1240 3010);
FORCEPROP 2 LASTPIN (-1250 2950) $PN DK23
J 0
(-1240 2960);
DISPLAY 0.617021 (-1240 2960);
PAINT ORANGE (-1240 2960);
FORCEPROP 2 LASTPIN (-1250 2900) $PN DK29
J 0
(-1240 2910);
DISPLAY 0.617021 (-1240 2910);
PAINT ORANGE (-1240 2910);
FORCEPROP 2 LASTPIN (-1250 2850) $PN DK35
J 0
(-1240 2860);
DISPLAY 0.617021 (-1240 2860);
PAINT ORANGE (-1240 2860);
FORCEPROP 2 LASTPIN (-1250 2800) $PN DK39
J 0
(-1240 2810);
DISPLAY 0.617021 (-1240 2810);
PAINT ORANGE (-1240 2810);
FORCEPROP 2 LASTPIN (-1250 2750) $PN DK41
J 0
(-1240 2760);
DISPLAY 0.617021 (-1240 2760);
PAINT ORANGE (-1240 2760);
FORCEPROP 2 LASTPIN (-1250 2700) $PN DK73
J 0
(-1240 2710);
DISPLAY 0.617021 (-1240 2710);
PAINT ORANGE (-1240 2710);
FORCEPROP 2 LASTPIN (-1250 2650) $PN DK75
J 0
(-1240 2660);
DISPLAY 0.617021 (-1240 2660);
PAINT ORANGE (-1240 2660);
FORCEPROP 2 LASTPIN (-1250 2600) $PN DK77
J 0
(-1240 2610);
DISPLAY 0.617021 (-1240 2610);
PAINT ORANGE (-1240 2610);
FORCEPROP 2 LASTPIN (-1250 2550) $PN DK83
J 0
(-1240 2560);
DISPLAY 0.617021 (-1240 2560);
PAINT ORANGE (-1240 2560);
FORCEPROP 2 LASTPIN (-1250 2500) $PN DK85
J 0
(-1240 2510);
DISPLAY 0.617021 (-1240 2510);
PAINT ORANGE (-1240 2510);
FORCEPROP 2 LASTPIN (-1250 2450) $PN DL16
J 0
(-1240 2460);
DISPLAY 0.617021 (-1240 2460);
PAINT ORANGE (-1240 2460);
FORCEPROP 2 LASTPIN (-1250 2400) $PN DL18
J 0
(-1240 2410);
DISPLAY 0.617021 (-1240 2410);
PAINT ORANGE (-1240 2410);
FORCEPROP 2 LASTPIN (-1250 2350) $PN DL4
J 0
(-1240 2360);
DISPLAY 0.617021 (-1240 2360);
PAINT ORANGE (-1240 2360);
FORCEPROP 2 LASTPIN (-1250 2300) $PN DL22
J 0
(-1240 2310);
DISPLAY 0.617021 (-1240 2310);
PAINT ORANGE (-1240 2310);
FORCEPROP 2 LASTPIN (-1250 2250) $PN DL24
J 0
(-1240 2260);
DISPLAY 0.617021 (-1240 2260);
PAINT ORANGE (-1240 2260);
FORCEPROP 2 LASTPIN (-1250 2200) $PN DL28
J 0
(-1240 2210);
DISPLAY 0.617021 (-1240 2210);
PAINT ORANGE (-1240 2210);
FORCEPROP 2 LASTPIN (-1250 2150) $PN DL30
J 0
(-1240 2160);
DISPLAY 0.617021 (-1240 2160);
PAINT ORANGE (-1240 2160);
FORCEPROP 2 LASTPIN (-1250 2100) $PN DL34
J 0
(-1240 2110);
DISPLAY 0.617021 (-1240 2110);
PAINT ORANGE (-1240 2110);
FORCEPROP 2 LASTPIN (-1250 2050) $PN DL36
J 0
(-1240 2060);
DISPLAY 0.617021 (-1240 2060);
PAINT ORANGE (-1240 2060);
FORCEPROP 2 LASTPIN (-1250 2000) $PN DL40
J 0
(-1240 2010);
DISPLAY 0.617021 (-1240 2010);
PAINT ORANGE (-1240 2010);
FORCEPROP 2 LASTPIN (-1250 1950) $PN DL68
J 0
(-1240 1960);
DISPLAY 0.617021 (-1240 1960);
PAINT ORANGE (-1240 1960);
FORCEPROP 2 LASTPIN (-1250 1900) $PN DL70
J 0
(-1240 1910);
DISPLAY 0.617021 (-1240 1910);
PAINT ORANGE (-1240 1910);
FORCEPROP 2 LASTPIN (-1250 1850) $PN DL74
J 0
(-1240 1860);
DISPLAY 0.617021 (-1240 1860);
PAINT ORANGE (-1240 1860);
FORCEPROP 2 LASTPIN (-1250 1800) $PN DL76
J 0
(-1240 1810);
DISPLAY 0.617021 (-1240 1810);
PAINT ORANGE (-1240 1810);
FORCEPROP 2 LASTPIN (-1250 1750) $PN DL78
J 0
(-1240 1760);
DISPLAY 0.617021 (-1240 1760);
PAINT ORANGE (-1240 1760);
FORCEPROP 2 LASTPIN (-1250 1700) $PN DL80
J 0
(-1240 1710);
DISPLAY 0.617021 (-1240 1710);
PAINT ORANGE (-1240 1710);
FORCEPROP 2 LASTPIN (-1250 1650) $PN DM15
J 0
(-1240 1660);
DISPLAY 0.617021 (-1240 1660);
PAINT ORANGE (-1240 1660);
FORCEPROP 2 LASTPIN (-1250 1600) $PN H45
J 0
(-1240 1610);
DISPLAY 0.617021 (-1240 1610);
PAINT ORANGE (-1240 1610);
FORCEPROP 2 LASTPIN (-1250 1550) $PN DM25
J 0
(-1240 1560);
DISPLAY 0.617021 (-1240 1560);
PAINT ORANGE (-1240 1560);
FORCEPROP 2 LASTPIN (-1250 1500) $PN DM27
J 0
(-1240 1510);
DISPLAY 0.617021 (-1240 1510);
PAINT ORANGE (-1240 1510);
FORCEPROP 2 LASTPIN (-1250 1450) $PN DM31
J 0
(-1240 1460);
DISPLAY 0.617021 (-1240 1460);
PAINT ORANGE (-1240 1460);
FORCEPROP 2 LASTPIN (-1250 1400) $PN DM33
J 0
(-1240 1410);
DISPLAY 0.617021 (-1240 1410);
PAINT ORANGE (-1240 1410);
FORCEPROP 2 LASTPIN (-1250 1350) $PN DM37
J 0
(-1240 1360);
DISPLAY 0.617021 (-1240 1360);
PAINT ORANGE (-1240 1360);
FORCEPROP 2 LASTPIN (-1250 1300) $PN DM39
J 0
(-1240 1310);
DISPLAY 0.617021 (-1240 1310);
PAINT ORANGE (-1240 1310);
FORCEPROP 2 LASTPIN (-1250 1250) $PN DM65
J 0
(-1240 1260);
DISPLAY 0.617021 (-1240 1260);
PAINT ORANGE (-1240 1260);
FORCEPROP 2 LASTPIN (-1250 1200) $PN DM73
J 0
(-1240 1210);
DISPLAY 0.617021 (-1240 1210);
PAINT ORANGE (-1240 1210);
FORCEPROP 2 LASTPIN (-1250 1150) $PN DM77
J 0
(-1240 1160);
DISPLAY 0.617021 (-1240 1160);
PAINT ORANGE (-1240 1160);
FORCEPROP 2 LASTPIN (-1250 1100) $PN DM83
J 0
(-1240 1110);
DISPLAY 0.617021 (-1240 1110);
PAINT ORANGE (-1240 1110);
FORCEPROP 2 LASTPIN (-1250 1050) $PN DN2
J 0
(-1240 1060);
DISPLAY 0.617021 (-1240 1060);
PAINT ORANGE (-1240 1060);
FORCEPROP 2 LASTPIN (-1250 1000) $PN BH17
J 0
(-1240 1010);
DISPLAY 0.617021 (-1240 1010);
PAINT ORANGE (-1240 1010);
FORCEPROP 2 LASTPIN (-1250 950) $PN DN12
J 0
(-1240 960);
DISPLAY 0.617021 (-1240 960);
PAINT ORANGE (-1240 960);
FORCEPROP 2 LASTPIN (-1250 900) $PN DN22
J 0
(-1240 910);
DISPLAY 0.617021 (-1240 910);
PAINT ORANGE (-1240 910);
FORCEPROP 2 LASTPIN (-1250 850) $PN DN26
J 0
(-1240 860);
DISPLAY 0.617021 (-1240 860);
PAINT ORANGE (-1240 860);
FORCEPROP 2 LASTPIN (-1250 800) $PN DN32
J 0
(-1240 810);
DISPLAY 0.617021 (-1240 810);
PAINT ORANGE (-1240 810);
FORCEPROP 2 LASTPIN (-1250 750) $PN DN38
J 0
(-1240 760);
DISPLAY 0.617021 (-1240 760);
PAINT ORANGE (-1240 760);
FORCEPROP 2 LASTPIN (-1250 700) $PN DN68
J 0
(-1240 710);
DISPLAY 0.617021 (-1240 710);
PAINT ORANGE (-1240 710);
FORCEPROP 2 LASTPIN (-1250 650) $PN DN72
J 0
(-1240 660);
DISPLAY 0.617021 (-1240 660);
PAINT ORANGE (-1240 660);
FORCEPROP 1 LAST PACK_TYPE BGA1
J 0
(-2400 4900);
PAINT SKYBLUE (-2400 4900);
DISPLAY INVISIBLE (-2400 4900);
FORCEPROP 2 LAST CDS_LIB chpset_lib
J 0
(-1850 2600);
PAINT ORANGE (-1850 2600);
DISPLAY INVISIBLE (-1850 2600);
FORCEPROP 2 LAST SEC_TYPE BGA1
J 0
(-2400 4900);
DISPLAY 1.021277 (-2400 4900);
PAINT ORANGE (-2400 4900);
DISPLAY INVISIBLE (-2400 4900);
FORCEPROP 2 LAST SEC 29
J 0
(-2400 4900);
DISPLAY 0.680851 (-2400 4900);
PAINT MONO (-2400 4900);
DISPLAY INVISIBLE (-2400 4900);
FORCEPROP 2 LAST CDS_LOCATION U5D1
J 0
(-2400 4850);
DISPLAY 0.617021 (-2400 4850);
PAINT AQUA (-2400 4850);
DISPLAY INVISIBLE (-2400 4850);
FORCEPROP 1 LAST PATH I285
J 0
(-1850 4800);
PAINT GREEN (-1850 4800);
DISPLAY INVISIBLE (-1850 4800);
FORCEPROP 0 LAST ROOM CPU0
J 0
(-2400 4950);
DISPLAY 1.021277 (-2400 4950);
PAINT ORANGE (-2400 4950);
DISPLAY INVISIBLE (-2400 4950);
FORCEADD SKX_EXT_B..30
(-175 2650);
FORCEPROP 1 LAST LOCATION U5D1
J 0
(-725 4900);
DISPLAY 0.617021 (-725 4900);
PAINT AQUA (-725 4900);
FORCEPROP 1 LAST PART_NUMBER TBD
J 0
(-725 500);
DISPLAY 0.617021 (-725 500);
PAINT BLUE (-725 500);
FORCEPROP 1 LAST MATERIAL IC
J 0
(-725 4850);
DISPLAY 0.617021 (-725 4850);
PAINT SKYBLUE (-725 4850);
FORCEPROP 2 LASTPIN (-775 4650) $PN DN78
J 2
(-785 4660);
DISPLAY 0.617021 (-785 4660);
PAINT ORANGE (-785 4660);
FORCEPROP 2 LASTPIN (-775 4600) $PN DP67
J 2
(-785 4610);
DISPLAY 0.617021 (-785 4610);
PAINT ORANGE (-785 4610);
FORCEPROP 2 LASTPIN (-775 4550) $PN DP69
J 2
(-785 4560);
DISPLAY 0.617021 (-785 4560);
PAINT ORANGE (-785 4560);
FORCEPROP 2 LASTPIN (-775 4500) $PN DP71
J 2
(-785 4510);
DISPLAY 0.617021 (-785 4510);
PAINT ORANGE (-785 4510);
FORCEPROP 2 LASTPIN (-775 4450) $PN DP81
J 2
(-785 4460);
DISPLAY 0.617021 (-785 4460);
PAINT ORANGE (-785 4460);
FORCEPROP 2 LASTPIN (-775 4400) $PN DP83
J 2
(-785 4410);
DISPLAY 0.617021 (-785 4410);
PAINT ORANGE (-785 4410);
FORCEPROP 2 LASTPIN (-775 4350) $PN BR26
J 2
(-785 4360);
DISPLAY 0.617021 (-785 4360);
PAINT ORANGE (-785 4360);
FORCEPROP 2 LASTPIN (-775 4300) $PN DR6
J 2
(-785 4310);
DISPLAY 0.617021 (-785 4310);
PAINT ORANGE (-785 4310);
FORCEPROP 2 LASTPIN (-775 4250) $PN CA20
J 2
(-785 4260);
DISPLAY 0.617021 (-785 4260);
PAINT ORANGE (-785 4260);
FORCEPROP 2 LASTPIN (-775 4200) $PN CL22
J 2
(-785 4210);
DISPLAY 0.617021 (-785 4210);
PAINT ORANGE (-785 4210);
FORCEPROP 2 LASTPIN (-775 4150) $PN DR20
J 2
(-785 4160);
DISPLAY 0.617021 (-785 4160);
PAINT ORANGE (-785 4160);
FORCEPROP 2 LASTPIN (-775 4100) $PN DR22
J 2
(-785 4110);
DISPLAY 0.617021 (-785 4110);
PAINT ORANGE (-785 4110);
FORCEPROP 2 LASTPIN (-775 4050) $PN DR24
J 2
(-785 4060);
DISPLAY 0.617021 (-785 4060);
PAINT ORANGE (-785 4060);
FORCEPROP 2 LASTPIN (-775 4000) $PN DR26
J 2
(-785 4010);
DISPLAY 0.617021 (-785 4010);
PAINT ORANGE (-785 4010);
FORCEPROP 2 LASTPIN (-775 3950) $PN DR28
J 2
(-785 3960);
DISPLAY 0.617021 (-785 3960);
PAINT ORANGE (-785 3960);
FORCEPROP 2 LASTPIN (-775 3900) $PN DR30
J 2
(-785 3910);
DISPLAY 0.617021 (-785 3910);
PAINT ORANGE (-785 3910);
FORCEPROP 2 LASTPIN (-775 3850) $PN DR32
J 2
(-785 3860);
DISPLAY 0.617021 (-785 3860);
PAINT ORANGE (-785 3860);
FORCEPROP 2 LASTPIN (-775 3800) $PN DR34
J 2
(-785 3810);
DISPLAY 0.617021 (-785 3810);
PAINT ORANGE (-785 3810);
FORCEPROP 2 LASTPIN (-775 3750) $PN DR36
J 2
(-785 3760);
DISPLAY 0.617021 (-785 3760);
PAINT ORANGE (-785 3760);
FORCEPROP 2 LASTPIN (-775 3700) $PN DR38
J 2
(-785 3710);
DISPLAY 0.617021 (-785 3710);
PAINT ORANGE (-785 3710);
FORCEPROP 2 LASTPIN (-775 3650) $PN DR40
J 2
(-785 3660);
DISPLAY 0.617021 (-785 3660);
PAINT ORANGE (-785 3660);
FORCEPROP 2 LASTPIN (-775 3600) $PN DR42
J 2
(-785 3610);
DISPLAY 0.617021 (-785 3610);
PAINT ORANGE (-785 3610);
FORCEPROP 2 LASTPIN (-775 3550) $PN DR66
J 2
(-785 3560);
DISPLAY 0.617021 (-785 3560);
PAINT ORANGE (-785 3560);
FORCEPROP 2 LASTPIN (-775 3500) $PN DR68
J 2
(-785 3510);
DISPLAY 0.617021 (-785 3510);
PAINT ORANGE (-785 3510);
FORCEPROP 2 LASTPIN (-775 3450) $PN DR70
J 2
(-785 3460);
DISPLAY 0.617021 (-785 3460);
PAINT ORANGE (-785 3460);
FORCEPROP 2 LASTPIN (-775 3400) $PN DR72
J 2
(-785 3410);
DISPLAY 0.617021 (-785 3410);
PAINT ORANGE (-785 3410);
FORCEPROP 2 LASTPIN (-775 3350) $PN DR74
J 2
(-785 3360);
DISPLAY 0.617021 (-785 3360);
PAINT ORANGE (-785 3360);
FORCEPROP 2 LASTPIN (-775 3300) $PN DR76
J 2
(-785 3310);
DISPLAY 0.617021 (-785 3310);
PAINT ORANGE (-785 3310);
FORCEPROP 2 LASTPIN (-775 3250) $PN DR78
J 2
(-785 3260);
DISPLAY 0.617021 (-785 3260);
PAINT ORANGE (-785 3260);
FORCEPROP 2 LASTPIN (-775 3200) $PN DT3
J 2
(-785 3210);
DISPLAY 0.617021 (-785 3210);
PAINT ORANGE (-785 3210);
FORCEPROP 2 LASTPIN (-775 3150) $PN DT17
J 2
(-785 3160);
DISPLAY 0.617021 (-785 3160);
PAINT ORANGE (-785 3160);
FORCEPROP 2 LASTPIN (-775 3100) $PN DH21
J 2
(-785 3110);
DISPLAY 0.617021 (-785 3110);
PAINT ORANGE (-785 3110);
FORCEPROP 2 LASTPIN (-775 3050) $PN DT65
J 2
(-785 3060);
DISPLAY 0.617021 (-785 3060);
PAINT ORANGE (-785 3060);
FORCEPROP 2 LASTPIN (-775 3000) $PN DT69
J 2
(-785 3010);
DISPLAY 0.617021 (-785 3010);
PAINT ORANGE (-785 3010);
FORCEPROP 2 LASTPIN (-775 2950) $PN DT79
J 2
(-785 2960);
DISPLAY 0.617021 (-785 2960);
PAINT ORANGE (-785 2960);
FORCEPROP 2 LASTPIN (-775 2900) $PN DT83
J 2
(-785 2910);
DISPLAY 0.617021 (-785 2910);
PAINT ORANGE (-785 2910);
FORCEPROP 2 LASTPIN (-775 2850) $PN DT85
J 2
(-785 2860);
DISPLAY 0.617021 (-785 2860);
PAINT ORANGE (-785 2860);
FORCEPROP 2 LASTPIN (-775 2800) $PN DU10
J 2
(-785 2810);
DISPLAY 0.617021 (-785 2810);
PAINT ORANGE (-785 2810);
FORCEPROP 2 LASTPIN (-775 2750) $PN DU14
J 2
(-785 2760);
DISPLAY 0.617021 (-785 2760);
PAINT ORANGE (-785 2760);
FORCEPROP 2 LASTPIN (-775 2700) $PN CN14
J 2
(-785 2710);
DISPLAY 0.617021 (-785 2710);
PAINT ORANGE (-785 2710);
FORCEPROP 2 LASTPIN (-775 2650) $PN DU22
J 2
(-785 2660);
DISPLAY 0.617021 (-785 2660);
PAINT ORANGE (-785 2660);
FORCEPROP 2 LASTPIN (-775 2600) $PN DU26
J 2
(-785 2610);
DISPLAY 0.617021 (-785 2610);
PAINT ORANGE (-785 2610);
FORCEPROP 2 LASTPIN (-775 2550) $PN DU32
J 2
(-785 2560);
DISPLAY 0.617021 (-785 2560);
PAINT ORANGE (-785 2560);
FORCEPROP 2 LASTPIN (-775 2500) $PN DU38
J 2
(-785 2510);
DISPLAY 0.617021 (-785 2510);
PAINT ORANGE (-785 2510);
FORCEPROP 2 LASTPIN (-775 2450) $PN DU70
J 2
(-785 2460);
DISPLAY 0.617021 (-785 2460);
PAINT ORANGE (-785 2460);
FORCEPROP 2 LASTPIN (-775 2400) $PN DU72
J 2
(-785 2410);
DISPLAY 0.617021 (-785 2410);
PAINT ORANGE (-785 2410);
FORCEPROP 2 LASTPIN (-775 2350) $PN DU78
J 2
(-785 2360);
DISPLAY 0.617021 (-785 2360);
PAINT ORANGE (-785 2360);
FORCEPROP 2 LASTPIN (-775 2300) $PN DU80
J 2
(-785 2310);
DISPLAY 0.617021 (-785 2310);
PAINT ORANGE (-785 2310);
FORCEPROP 2 LASTPIN (-775 2250) $PN DU82
J 2
(-785 2260);
DISPLAY 0.617021 (-785 2260);
PAINT ORANGE (-785 2260);
FORCEPROP 2 LASTPIN (-775 2200) $PN DU84
J 2
(-785 2210);
DISPLAY 0.617021 (-785 2210);
PAINT ORANGE (-785 2210);
FORCEPROP 2 LASTPIN (-775 2150) $PN DV21
J 2
(-785 2160);
DISPLAY 0.617021 (-785 2160);
PAINT ORANGE (-785 2160);
FORCEPROP 2 LASTPIN (-775 2100) $PN DV25
J 2
(-785 2110);
DISPLAY 0.617021 (-785 2110);
PAINT ORANGE (-785 2110);
FORCEPROP 2 LASTPIN (-775 2050) $PN DV27
J 2
(-785 2060);
DISPLAY 0.617021 (-785 2060);
PAINT ORANGE (-785 2060);
FORCEPROP 2 LASTPIN (-775 2000) $PN DV31
J 2
(-785 2010);
DISPLAY 0.617021 (-785 2010);
PAINT ORANGE (-785 2010);
FORCEPROP 2 LASTPIN (-775 1950) $PN DV33
J 2
(-785 1960);
DISPLAY 0.617021 (-785 1960);
PAINT ORANGE (-785 1960);
FORCEPROP 2 LASTPIN (-775 1900) $PN DV37
J 2
(-785 1910);
DISPLAY 0.617021 (-785 1910);
PAINT ORANGE (-785 1910);
FORCEPROP 2 LASTPIN (-775 1850) $PN DV39
J 2
(-785 1860);
DISPLAY 0.617021 (-785 1860);
PAINT ORANGE (-785 1860);
FORCEPROP 2 LASTPIN (-775 1800) $PN DV73
J 2
(-785 1810);
DISPLAY 0.617021 (-785 1810);
PAINT ORANGE (-785 1810);
FORCEPROP 2 LASTPIN (-775 1750) $PN DV77
J 2
(-785 1760);
DISPLAY 0.617021 (-785 1760);
PAINT ORANGE (-785 1760);
FORCEPROP 2 LASTPIN (-775 1700) $PN DV81
J 2
(-785 1710);
DISPLAY 0.617021 (-785 1710);
PAINT ORANGE (-785 1710);
FORCEPROP 2 LASTPIN (-775 1650) $PN DW12
J 2
(-785 1660);
DISPLAY 0.617021 (-785 1660);
PAINT ORANGE (-785 1660);
FORCEPROP 2 LASTPIN (-775 1600) $PN DW20
J 2
(-785 1610);
DISPLAY 0.617021 (-785 1610);
PAINT ORANGE (-785 1610);
FORCEPROP 2 LASTPIN (-775 1550) $PN DW24
J 2
(-785 1560);
DISPLAY 0.617021 (-785 1560);
PAINT ORANGE (-785 1560);
FORCEPROP 2 LASTPIN (-775 1500) $PN DW28
J 2
(-785 1510);
DISPLAY 0.617021 (-785 1510);
PAINT ORANGE (-785 1510);
FORCEPROP 2 LASTPIN (-775 1450) $PN DW30
J 2
(-785 1460);
DISPLAY 0.617021 (-785 1460);
PAINT ORANGE (-785 1460);
FORCEPROP 2 LASTPIN (-775 1400) $PN DW34
J 2
(-785 1410);
DISPLAY 0.617021 (-785 1410);
PAINT ORANGE (-785 1410);
FORCEPROP 2 LASTPIN (-775 1350) $PN DW36
J 2
(-785 1360);
DISPLAY 0.617021 (-785 1360);
PAINT ORANGE (-785 1360);
FORCEPROP 2 LASTPIN (-775 1300) $PN DW40
J 2
(-785 1310);
DISPLAY 0.617021 (-785 1310);
PAINT ORANGE (-785 1310);
FORCEPROP 2 LASTPIN (-775 1250) $PN DW64
J 2
(-785 1260);
DISPLAY 0.617021 (-785 1260);
PAINT ORANGE (-785 1260);
FORCEPROP 2 LASTPIN (-775 1200) $PN DW66
J 2
(-785 1210);
DISPLAY 0.617021 (-785 1210);
PAINT ORANGE (-785 1210);
FORCEPROP 2 LASTPIN (-775 1150) $PN DW68
J 2
(-785 1160);
DISPLAY 0.617021 (-785 1160);
PAINT ORANGE (-785 1160);
FORCEPROP 2 LASTPIN (-775 1100) $PN DW70
J 2
(-785 1110);
DISPLAY 0.617021 (-785 1110);
PAINT ORANGE (-785 1110);
FORCEPROP 2 LASTPIN (-775 1050) $PN DW72
J 2
(-785 1060);
DISPLAY 0.617021 (-785 1060);
PAINT ORANGE (-785 1060);
FORCEPROP 2 LASTPIN (-775 1000) $PN DW74
J 2
(-785 1010);
DISPLAY 0.617021 (-785 1010);
PAINT ORANGE (-785 1010);
FORCEPROP 2 LASTPIN (-775 950) $PN DW76
J 2
(-785 960);
DISPLAY 0.617021 (-785 960);
PAINT ORANGE (-785 960);
FORCEPROP 2 LASTPIN (-775 900) $PN DW8
J 2
(-785 910);
DISPLAY 0.617021 (-785 910);
PAINT ORANGE (-785 910);
FORCEPROP 2 LASTPIN (-775 850) $PN DW82
J 2
(-785 860);
DISPLAY 0.617021 (-785 860);
PAINT ORANGE (-785 860);
FORCEPROP 2 LASTPIN (-775 800) $PN DW84
J 2
(-785 810);
DISPLAY 0.617021 (-785 810);
PAINT ORANGE (-785 810);
FORCEPROP 2 LASTPIN (-775 750) $PN DY5
J 2
(-785 760);
DISPLAY 0.617021 (-785 760);
PAINT ORANGE (-785 760);
FORCEPROP 2 LASTPIN (-775 700) $PN DY19
J 2
(-785 710);
DISPLAY 0.617021 (-785 710);
PAINT ORANGE (-785 710);
FORCEPROP 2 LASTPIN (425 4650) $PN DY23
J 0
(435 4660);
DISPLAY 0.617021 (435 4660);
PAINT ORANGE (435 4660);
FORCEPROP 2 LASTPIN (425 4600) $PN DY29
J 0
(435 4610);
DISPLAY 0.617021 (435 4610);
PAINT ORANGE (435 4610);
FORCEPROP 2 LASTPIN (425 4550) $PN DY35
J 0
(435 4560);
DISPLAY 0.617021 (435 4560);
PAINT ORANGE (435 4560);
FORCEPROP 2 LASTPIN (425 4500) $PN DY41
J 0
(435 4510);
DISPLAY 0.617021 (435 4510);
PAINT ORANGE (435 4510);
FORCEPROP 2 LASTPIN (425 4450) $PN DY71
J 0
(435 4460);
DISPLAY 0.617021 (435 4460);
PAINT ORANGE (435 4460);
FORCEPROP 2 LASTPIN (425 4400) $PN DY75
J 0
(435 4410);
DISPLAY 0.617021 (435 4410);
PAINT ORANGE (435 4410);
FORCEPROP 2 LASTPIN (425 4350) $PN EA6
J 0
(435 4360);
DISPLAY 0.617021 (435 4360);
PAINT ORANGE (435 4360);
FORCEPROP 2 LASTPIN (425 4300) $PN J16
J 0
(435 4310);
DISPLAY 0.617021 (435 4310);
PAINT ORANGE (435 4310);
FORCEPROP 2 LASTPIN (425 4250) $PN EA16
J 0
(435 4260);
DISPLAY 0.617021 (435 4260);
PAINT ORANGE (435 4260);
FORCEPROP 2 LASTPIN (425 4200) $PN EA20
J 0
(435 4210);
DISPLAY 0.617021 (435 4210);
PAINT ORANGE (435 4210);
FORCEPROP 2 LASTPIN (425 4150) $PN EA22
J 0
(435 4160);
DISPLAY 0.617021 (435 4160);
PAINT ORANGE (435 4160);
FORCEPROP 2 LASTPIN (425 4100) $PN EA42
J 0
(435 4110);
DISPLAY 0.617021 (435 4110);
PAINT ORANGE (435 4110);
FORCEPROP 2 LASTPIN (425 4050) $PN EA64
J 0
(435 4060);
DISPLAY 0.617021 (435 4060);
PAINT ORANGE (435 4060);
FORCEPROP 2 LASTPIN (425 4000) $PN EA70
J 0
(435 4010);
DISPLAY 0.617021 (435 4010);
PAINT ORANGE (435 4010);
FORCEPROP 2 LASTPIN (425 3950) $PN EA76
J 0
(435 3960);
DISPLAY 0.617021 (435 3960);
PAINT ORANGE (435 3960);
FORCEPROP 2 LASTPIN (425 3900) $PN EA78
J 0
(435 3910);
DISPLAY 0.617021 (435 3910);
PAINT ORANGE (435 3910);
FORCEPROP 2 LASTPIN (425 3850) $PN EA80
J 0
(435 3860);
DISPLAY 0.617021 (435 3860);
PAINT ORANGE (435 3860);
FORCEPROP 2 LASTPIN (425 3800) $PN EA82
J 0
(435 3810);
DISPLAY 0.617021 (435 3810);
PAINT ORANGE (435 3810);
FORCEPROP 2 LASTPIN (425 3750) $PN EB13
J 0
(435 3760);
DISPLAY 0.617021 (435 3760);
PAINT ORANGE (435 3760);
FORCEPROP 2 LASTPIN (425 3700) $PN BR18
J 0
(435 3710);
DISPLAY 0.617021 (435 3710);
PAINT ORANGE (435 3710);
FORCEPROP 2 LASTPIN (425 3650) $PN EB23
J 0
(435 3660);
DISPLAY 0.617021 (435 3660);
PAINT ORANGE (435 3660);
FORCEPROP 2 LASTPIN (425 3600) $PN EB25
J 0
(435 3610);
DISPLAY 0.617021 (435 3610);
PAINT ORANGE (435 3610);
FORCEPROP 2 LASTPIN (425 3550) $PN EB27
J 0
(435 3560);
DISPLAY 0.617021 (435 3560);
PAINT ORANGE (435 3560);
FORCEPROP 2 LASTPIN (425 3500) $PN EB29
J 0
(435 3510);
DISPLAY 0.617021 (435 3510);
PAINT ORANGE (435 3510);
FORCEPROP 2 LASTPIN (425 3450) $PN EB31
J 0
(435 3460);
DISPLAY 0.617021 (435 3460);
PAINT ORANGE (435 3460);
FORCEPROP 2 LASTPIN (425 3400) $PN EB33
J 0
(435 3410);
DISPLAY 0.617021 (435 3410);
PAINT ORANGE (435 3410);
FORCEPROP 2 LASTPIN (425 3350) $PN EB35
J 0
(435 3360);
DISPLAY 0.617021 (435 3360);
PAINT ORANGE (435 3360);
FORCEPROP 2 LASTPIN (425 3300) $PN EB37
J 0
(435 3310);
DISPLAY 0.617021 (435 3310);
PAINT ORANGE (435 3310);
FORCEPROP 2 LASTPIN (425 3250) $PN EB39
J 0
(435 3260);
DISPLAY 0.617021 (435 3260);
PAINT ORANGE (435 3260);
FORCEPROP 2 LASTPIN (425 3200) $PN EB41
J 0
(435 3210);
DISPLAY 0.617021 (435 3210);
PAINT ORANGE (435 3210);
FORCEPROP 2 LASTPIN (425 3150) $PN EB65
J 0
(435 3160);
DISPLAY 0.617021 (435 3160);
PAINT ORANGE (435 3160);
FORCEPROP 2 LASTPIN (425 3100) $PN EB69
J 0
(435 3110);
DISPLAY 0.617021 (435 3110);
PAINT ORANGE (435 3110);
FORCEPROP 2 LASTPIN (425 3050) $PN EC10
J 0
(435 3060);
DISPLAY 0.617021 (435 3060);
PAINT ORANGE (435 3060);
FORCEPROP 2 LASTPIN (425 3000) $PN EC70
J 0
(435 3010);
DISPLAY 0.617021 (435 3010);
PAINT ORANGE (435 3010);
FORCEPROP 2 LASTPIN (425 2950) $PN EC72
J 0
(435 2960);
DISPLAY 0.617021 (435 2960);
PAINT ORANGE (435 2960);
FORCEPROP 2 LASTPIN (425 2900) $PN EC74
J 0
(435 2910);
DISPLAY 0.617021 (435 2910);
PAINT ORANGE (435 2910);
FORCEPROP 2 LASTPIN (425 2850) $PN EC76
J 0
(435 2860);
DISPLAY 0.617021 (435 2860);
PAINT ORANGE (435 2860);
FORCEPROP 2 LASTPIN (425 2800) $PN ED11
J 0
(435 2810);
DISPLAY 0.617021 (435 2810);
PAINT ORANGE (435 2810);
FORCEPROP 2 LASTPIN (425 2750) $PN ED15
J 0
(435 2760);
DISPLAY 0.617021 (435 2760);
PAINT ORANGE (435 2760);
FORCEPROP 2 LASTPIN (425 2700) $PN ED23
J 0
(435 2710);
DISPLAY 0.617021 (435 2710);
PAINT ORANGE (435 2710);
FORCEPROP 2 LASTPIN (425 2650) $PN ED29
J 0
(435 2660);
DISPLAY 0.617021 (435 2660);
PAINT ORANGE (435 2660);
FORCEPROP 2 LASTPIN (425 2600) $PN ED35
J 0
(435 2610);
DISPLAY 0.617021 (435 2610);
PAINT ORANGE (435 2610);
FORCEPROP 2 LASTPIN (425 2550) $PN ED77
J 0
(435 2560);
DISPLAY 0.617021 (435 2560);
PAINT ORANGE (435 2560);
FORCEPROP 2 LASTPIN (425 2500) $PN EE24
J 0
(435 2510);
DISPLAY 0.617021 (435 2510);
PAINT ORANGE (435 2510);
FORCEPROP 2 LASTPIN (425 2450) $PN EE28
J 0
(435 2460);
DISPLAY 0.617021 (435 2460);
PAINT ORANGE (435 2460);
FORCEPROP 2 LASTPIN (425 2400) $PN EE30
J 0
(435 2410);
DISPLAY 0.617021 (435 2410);
PAINT ORANGE (435 2410);
FORCEPROP 2 LASTPIN (425 2350) $PN EE34
J 0
(435 2360);
DISPLAY 0.617021 (435 2360);
PAINT ORANGE (435 2360);
FORCEPROP 2 LASTPIN (425 2300) $PN EE36
J 0
(435 2310);
DISPLAY 0.617021 (435 2310);
PAINT ORANGE (435 2310);
FORCEPROP 2 LASTPIN (425 2250) $PN EE70
J 0
(435 2260);
DISPLAY 0.617021 (435 2260);
PAINT ORANGE (435 2260);
FORCEPROP 2 LASTPIN (425 2200) $PN EE76
J 0
(435 2210);
DISPLAY 0.617021 (435 2210);
PAINT ORANGE (435 2210);
FORCEPROP 2 LASTPIN (425 2150) $PN EE78
J 0
(435 2160);
DISPLAY 0.617021 (435 2160);
PAINT ORANGE (435 2160);
FORCEPROP 2 LASTPIN (425 2100) $PN EF71
J 0
(435 2110);
DISPLAY 0.617021 (435 2110);
PAINT ORANGE (435 2110);
FORCEPROP 2 LASTPIN (425 2050) $PN EF75
J 0
(435 2060);
DISPLAY 0.617021 (435 2060);
PAINT ORANGE (435 2060);
FORCEPROP 2 LASTPIN (425 2000) $PN EF79
J 0
(435 2010);
DISPLAY 0.617021 (435 2010);
PAINT ORANGE (435 2010);
FORCEPROP 1 LAST PACK_TYPE BGA1
J 0
(-725 4950);
PAINT SKYBLUE (-725 4950);
DISPLAY INVISIBLE (-725 4950);
FORCEPROP 2 LAST CDS_LIB chpset_lib
J 0
(-175 2650);
PAINT ORANGE (-175 2650);
DISPLAY INVISIBLE (-175 2650);
FORCEPROP 2 LAST SEC_TYPE BGA1
J 0
(-725 4950);
DISPLAY 1.021277 (-725 4950);
PAINT ORANGE (-725 4950);
DISPLAY INVISIBLE (-725 4950);
FORCEPROP 2 LAST SEC 30
J 0
(-725 4950);
DISPLAY 0.680851 (-725 4950);
PAINT MONO (-725 4950);
DISPLAY INVISIBLE (-725 4950);
FORCEPROP 2 LAST CDS_LOCATION U5D1
J 0
(-725 4900);
DISPLAY 0.617021 (-725 4900);
PAINT AQUA (-725 4900);
DISPLAY INVISIBLE (-725 4900);
FORCEPROP 1 LAST PATH I286
J 0
(-175 4850);
PAINT GREEN (-175 4850);
DISPLAY INVISIBLE (-175 4850);
FORCEPROP 0 LAST ROOM CPU0
J 0
(-725 5000);
DISPLAY 1.021277 (-725 5000);
PAINT ORANGE (-725 5000);
DISPLAY INVISIBLE (-725 5000);
FORCEADD DESIGN_NOTE..1
(-4900 250);
FORCEPROP 0 LAST L1 CPU SYMBOLS 1-30 ARE PRELIMINARY AND SUBJECT TO CHANGE
J 0
(-5100 125);
DISPLAY 1.021277 (-5100 125);
PAINT ORANGE (-5100 125);
FORCEPROP 2 LAST CDS_LIB mstr_symbols
J 0
(-4900 250);
PAINT ORANGE (-4900 250);
DISPLAY INVISIBLE (-4900 250);
FORCEPROP 1 LAST COMMENT_BODY TRUE
J 0
(-4875 350);
DISPLAY 0.978723 (-4875 350);
PAINT ORANGE (-4875 350);
DISPLAY INVISIBLE (-4875 350);
FORCEADD INTEL_CORP_BPAGE..1
(1500 75);
FORCEPROP 1 LAST CDS_CON_LAST_MODIFIED Tue Dec 01 11:51:25 2015
J 0
(75 400);
DISPLAY 1.340426 (75 400);
PAINT GREEN (75 400);
DISPLAY INVISIBLE (75 400);
FORCEPROP 1 LAST CUSTOM_TXT_CDS <CURRENT_DESIGN_SHEET> OF <TOTAL_DESIGN_SHEETS>
J 0
(1000 100);
PAINT GREEN (1000 100);
FORCEPROP 1 LAST CUSTOM_TXT_CDS <CON_LAST_MODIFIED>
J 0
(-425 425);
PAINT GREEN (-425 425);
FORCEPROP 2 LAST CUSTOM_TXT_CDS <XR_PAGE_TITLE>
J 0
(-6390 5325);
DISPLAY 0.638298 (-6390 5325);
PAINT PINK (-6390 5325);
DISPLAY INVISIBLE (-6390 5325);
FORCEPROP 1 LAST SCH_ADDRESS3 Santa Clara, CA 95052-8119
J 0
(-2475 100);
DISPLAY 0.617021 (-2475 100);
PAINT GREEN (-2475 100);
FORCEPROP 1 LAST SCH_ADDRESS2 P.O. BOX 58119
J 0
(-2475 150);
DISPLAY 0.617021 (-2475 150);
PAINT GREEN (-2475 150);
FORCEPROP 1 LAST SCH_ADDRESS1 2200 Mission College Blvd.
J 0
(-2475 200);
DISPLAY 0.617021 (-2475 200);
PAINT GREEN (-2475 200);
FORCEPROP 1 LAST SCH_TITLE SKYLAKE - SKT0 - 21 OF 21
J 0
(-6450 125);
DISPLAY 1.212766 (-6450 125);
PAINT GREEN (-6450 125);
FORCEPROP 1 LAST SCH_NUMBER H4694802
J 0
(200 225);
DISPLAY 1.212766 (200 225);
PAINT YELLOW (200 225);
FORCEPROP 1 LAST SCH_DEPT BESD
J 1
(-2950 175);
DISPLAY 1.212766 (-2950 175);
PAINT YELLOW (-2950 175);
FORCEPROP 1 LAST SCH_REV 2.420
J 0
(1250 225);
DISPLAY 0.978723 (1250 225);
PAINT YELLOW (1250 225);
FORCEPROP 2 LAST PAGE_BORDER TRUE
J 0
(-6390 5325);
DISPLAY 0.851064 (-6390 5325);
PAINT PINK (-6390 5325);
DISPLAY INVISIBLE (-6390 5325);
FORCEPROP 2 LAST CDS_LIB mstr_symbols
J 0
(1500 75);
PAINT ORANGE (1500 75);
DISPLAY INVISIBLE (1500 75);
FORCEPROP 1 LAST COMMENT_BODY TRUE
J 0
(1512 87);
DISPLAY 0.638298 (1512 87);
PAINT GREEN (1512 87);
DISPLAY INVISIBLE (1512 87);
FORCEPROP 2 LAST CDS_XR_PAGE_TITLE CR-41 : @BASEBOARD_FAB2_LIB.BASEBOARD_FAB2(SCH_1):PAGE41
J 0
(-6390 5325);
DISPLAY 0.638298 (-6390 5325);
PAINT PINK (-6390 5325);
DISPLAY INVISIBLE (-6390 5325);
WIRE 16 -1 (-4675 4650)(-4475 4650);
WIRE 16 -1 (-4475 4650)(-4475 4600);
WIRE 16 -1 (-4675 4600)(-4475 4600);
WIRE 16 -1 (-4475 4600)(-4475 4550);
WIRE 16 -1 (-4675 4550)(-4475 4550);
WIRE 16 -1 (-4475 4550)(-4475 4500);
WIRE 16 -1 (-4675 4500)(-4475 4500);
WIRE 16 -1 (-4475 4500)(-4475 4450);
WIRE 16 -1 (-4675 4450)(-4475 4450);
WIRE 16 -1 (-4475 4450)(-4475 4400);
WIRE 16 -1 (-4675 4400)(-4475 4400);
WIRE 16 -1 (-4475 4400)(-4475 4350);
WIRE 16 -1 (-4675 4350)(-4475 4350);
WIRE 16 -1 (-4475 4350)(-4475 4300);
WIRE 16 -1 (-4675 4300)(-4475 4300);
WIRE 16 -1 (-4475 4300)(-4475 4250);
WIRE 16 -1 (-4675 4250)(-4475 4250);
WIRE 16 -1 (-4475 4250)(-4475 4200);
WIRE 16 -1 (-4675 4200)(-4475 4200);
WIRE 16 -1 (-4475 4200)(-4475 4150);
WIRE 16 -1 (-4675 4150)(-4475 4150);
WIRE 16 -1 (-4475 4150)(-4475 4100);
WIRE 16 -1 (-4675 4100)(-4475 4100);
WIRE 16 -1 (-4475 4100)(-4475 4050);
WIRE 16 -1 (-4675 4050)(-4475 4050);
WIRE 16 -1 (-4475 4050)(-4475 4000);
WIRE 16 -1 (-4675 4000)(-4475 4000);
WIRE 16 -1 (-4475 4000)(-4475 3950);
WIRE 16 -1 (-4675 3950)(-4475 3950);
WIRE 16 -1 (-4475 3950)(-4475 3900);
WIRE 16 -1 (-4675 3900)(-4475 3900);
WIRE 16 -1 (-4475 3900)(-4475 3850);
WIRE 16 -1 (-4675 3850)(-4475 3850);
WIRE 16 -1 (-4475 3850)(-4475 3800);
WIRE 16 -1 (-4675 3800)(-4475 3800);
WIRE 16 -1 (-4475 3800)(-4475 3750);
WIRE 16 -1 (-4675 3750)(-4475 3750);
WIRE 16 -1 (-4475 3750)(-4475 3700);
WIRE 16 -1 (-4675 3700)(-4475 3700);
WIRE 16 -1 (-4475 3700)(-4475 3650);
WIRE 16 -1 (-4675 3650)(-4475 3650);
WIRE 16 -1 (-4475 3650)(-4475 3600);
WIRE 16 -1 (-4675 3600)(-4475 3600);
WIRE 16 -1 (-4475 3600)(-4475 3550);
WIRE 16 -1 (-4675 3550)(-4475 3550);
WIRE 16 -1 (-4475 3550)(-4475 3500);
WIRE 16 -1 (-4675 3500)(-4475 3500);
WIRE 16 -1 (-4475 3500)(-4475 3450);
WIRE 16 -1 (-4675 3450)(-4475 3450);
WIRE 16 -1 (-4475 3450)(-4475 3400);
WIRE 16 -1 (-4675 3400)(-4475 3400);
WIRE 16 -1 (-4475 3400)(-4475 3350);
WIRE 16 -1 (-4675 3350)(-4475 3350);
WIRE 16 -1 (-4475 3350)(-4475 3300);
WIRE 16 -1 (-4675 3300)(-4475 3300);
WIRE 16 -1 (-4475 3300)(-4475 3250);
WIRE 16 -1 (-4675 3250)(-4475 3250);
WIRE 16 -1 (-4475 3250)(-4475 3200);
WIRE 16 -1 (-4675 3200)(-4475 3200);
WIRE 16 -1 (-4475 3200)(-4475 3150);
WIRE 16 -1 (-4675 3150)(-4475 3150);
WIRE 16 -1 (-4475 3150)(-4475 3100);
WIRE 16 -1 (-4675 3100)(-4475 3100);
WIRE 16 -1 (-4475 3100)(-4475 3050);
WIRE 16 -1 (-4675 3050)(-4475 3050);
WIRE 16 -1 (-4475 3050)(-4475 3000);
WIRE 16 -1 (-4675 3000)(-4475 3000);
WIRE 16 -1 (-4475 3000)(-4475 2950);
WIRE 16 -1 (-4675 2950)(-4475 2950);
WIRE 16 -1 (-4475 2950)(-4475 2900);
WIRE 16 -1 (-4675 2900)(-4475 2900);
WIRE 16 -1 (-4475 2900)(-4475 2850);
WIRE 16 -1 (-4675 2850)(-4475 2850);
WIRE 16 -1 (-4475 2850)(-4475 2800);
WIRE 16 -1 (-4675 2800)(-4475 2800);
WIRE 16 -1 (-4475 2800)(-4475 2750);
WIRE 16 -1 (-4675 2750)(-4475 2750);
WIRE 16 -1 (-4475 2750)(-4475 2700);
WIRE 16 -1 (-4675 2700)(-4475 2700);
WIRE 16 -1 (-4475 2700)(-4475 2650);
WIRE 16 -1 (-4675 2650)(-4475 2650);
WIRE 16 -1 (-4475 2650)(-4475 2600);
WIRE 16 -1 (-4675 2600)(-4475 2600);
WIRE 16 -1 (-4475 2600)(-4475 2550);
WIRE 16 -1 (-4675 2550)(-4475 2550);
WIRE 16 -1 (-4475 2550)(-4475 2500);
WIRE 16 -1 (-4675 2500)(-4475 2500);
WIRE 16 -1 (-4475 2500)(-4475 2450);
WIRE 16 -1 (-4675 2450)(-4475 2450);
WIRE 16 -1 (-4475 2450)(-4475 2400);
WIRE 16 -1 (-4675 2400)(-4475 2400);
WIRE 16 -1 (-4475 2400)(-4475 2350);
WIRE 16 -1 (-4675 2350)(-4475 2350);
WIRE 16 -1 (-4475 2350)(-4475 2300);
WIRE 16 -1 (-4675 2300)(-4475 2300);
WIRE 16 -1 (-4475 2300)(-4475 2250);
WIRE 16 -1 (-4675 2250)(-4475 2250);
WIRE 16 -1 (-4475 2250)(-4475 2200);
WIRE 16 -1 (-4675 2200)(-4475 2200);
WIRE 16 -1 (-4475 2200)(-4475 2150);
WIRE 16 -1 (-4675 2150)(-4475 2150);
WIRE 16 -1 (-4475 2150)(-4475 2100);
WIRE 16 -1 (-4675 2100)(-4475 2100);
WIRE 16 -1 (-4475 2100)(-4475 2050);
WIRE 16 -1 (-4675 2050)(-4475 2050);
WIRE 16 -1 (-4475 2050)(-4475 2000);
WIRE 16 -1 (-4675 2000)(-4475 2000);
WIRE 16 -1 (-4475 2000)(-4475 1950);
WIRE 16 -1 (-4675 1950)(-4475 1950);
WIRE 16 -1 (-4475 1950)(-4475 1900);
WIRE 16 -1 (-4675 1900)(-4475 1900);
WIRE 16 -1 (-4475 1900)(-4475 1850);
WIRE 16 -1 (-4675 1850)(-4475 1850);
WIRE 16 -1 (-4475 1850)(-4475 1800);
WIRE 16 -1 (-4675 1800)(-4475 1800);
WIRE 16 -1 (-4475 1800)(-4475 1750);
WIRE 16 -1 (-4675 1750)(-4475 1750);
WIRE 16 -1 (-4475 1750)(-4475 1700);
WIRE 16 -1 (-4675 1700)(-4475 1700);
WIRE 16 -1 (-4475 1700)(-4475 1650);
WIRE 16 -1 (-4675 1650)(-4475 1650);
WIRE 16 -1 (-4475 1650)(-4475 1600);
WIRE 16 -1 (-4675 1600)(-4475 1600);
WIRE 16 -1 (-4475 1600)(-4475 1550);
WIRE 16 -1 (-4675 1550)(-4475 1550);
WIRE 16 -1 (-4475 1550)(-4475 1500);
WIRE 16 -1 (-4675 1500)(-4475 1500);
WIRE 16 -1 (-4475 1500)(-4475 1450);
WIRE 16 -1 (-4675 1450)(-4475 1450);
WIRE 16 -1 (-4475 1450)(-4475 1400);
WIRE 16 -1 (-4675 1400)(-4475 1400);
WIRE 16 -1 (-4475 1400)(-4475 1350);
WIRE 16 -1 (-4675 1350)(-4475 1350);
WIRE 16 -1 (-4475 1350)(-4475 1300);
WIRE 16 -1 (-4675 1300)(-4475 1300);
WIRE 16 -1 (-4475 1300)(-4475 1250);
WIRE 16 -1 (-4675 1250)(-4475 1250);
WIRE 16 -1 (-4475 1250)(-4475 1200);
WIRE 16 -1 (-4675 1200)(-4475 1200);
WIRE 16 -1 (-4475 1200)(-4475 1150);
WIRE 16 -1 (-4675 1150)(-4475 1150);
WIRE 16 -1 (-4475 1150)(-4475 1100);
WIRE 16 -1 (-4675 1100)(-4475 1100);
WIRE 16 -1 (-4475 1100)(-4475 1050);
WIRE 16 -1 (-4675 1050)(-4475 1050);
WIRE 16 -1 (-4475 1050)(-4475 1000);
WIRE 16 -1 (-4675 1000)(-4475 1000);
WIRE 16 -1 (-4475 1000)(-4475 950);
WIRE 16 -1 (-4675 950)(-4475 950);
WIRE 16 -1 (-4475 950)(-4475 900);
WIRE 16 -1 (-4675 900)(-4475 900);
WIRE 16 -1 (-4475 900)(-4475 850);
WIRE 16 -1 (-4675 850)(-4475 850);
WIRE 16 -1 (-4475 850)(-4475 800);
WIRE 16 -1 (-4675 800)(-4475 800);
WIRE 16 -1 (-4475 800)(-4475 750);
WIRE 16 -1 (-4675 750)(-4475 750);
WIRE 16 -1 (-4475 750)(-4475 700);
WIRE 16 -1 (-4675 700)(-4475 700);
WIRE 16 -1 (-4475 700)(-4475 600);
WIRE 16 -1 (-2975 4650)(-2800 4650);
WIRE 16 -1 (-2800 4650)(-2800 4600);
WIRE 16 -1 (-2975 4600)(-2800 4600);
WIRE 16 -1 (-2800 4600)(-2800 4550);
WIRE 16 -1 (-2975 4550)(-2800 4550);
WIRE 16 -1 (-2800 4550)(-2800 4500);
WIRE 16 -1 (-2975 4500)(-2800 4500);
WIRE 16 -1 (-2800 4500)(-2800 4450);
WIRE 16 -1 (-2975 4450)(-2800 4450);
WIRE 16 -1 (-2800 4450)(-2800 4400);
WIRE 16 -1 (-2975 4400)(-2800 4400);
WIRE 16 -1 (-2800 4400)(-2800 4350);
WIRE 16 -1 (-2975 4350)(-2800 4350);
WIRE 16 -1 (-2800 4350)(-2800 4300);
WIRE 16 -1 (-2975 4300)(-2800 4300);
WIRE 16 -1 (-2800 4300)(-2800 4250);
WIRE 16 -1 (-2975 4250)(-2800 4250);
WIRE 16 -1 (-2800 4250)(-2800 4200);
WIRE 16 -1 (-2975 4200)(-2800 4200);
WIRE 16 -1 (-2800 4200)(-2800 4150);
WIRE 16 -1 (-2975 4150)(-2800 4150);
WIRE 16 -1 (-2800 4150)(-2800 4100);
WIRE 16 -1 (-2975 4100)(-2800 4100);
WIRE 16 -1 (-2800 4100)(-2800 4050);
WIRE 16 -1 (-2975 4050)(-2800 4050);
WIRE 16 -1 (-2800 4050)(-2800 4000);
WIRE 16 -1 (-2975 4000)(-2800 4000);
WIRE 16 -1 (-2800 4000)(-2800 3950);
WIRE 16 -1 (-2975 3950)(-2800 3950);
WIRE 16 -1 (-2800 3950)(-2800 3900);
WIRE 16 -1 (-2975 3900)(-2800 3900);
WIRE 16 -1 (-2800 3900)(-2800 3850);
WIRE 16 -1 (-2975 3850)(-2800 3850);
WIRE 16 -1 (-2800 3850)(-2800 3800);
WIRE 16 -1 (-2975 3800)(-2800 3800);
WIRE 16 -1 (-2800 3800)(-2800 3750);
WIRE 16 -1 (-2975 3750)(-2800 3750);
WIRE 16 -1 (-2800 3750)(-2800 3700);
WIRE 16 -1 (-2975 3700)(-2800 3700);
WIRE 16 -1 (-2800 3700)(-2800 3650);
WIRE 16 -1 (-2975 3650)(-2800 3650);
WIRE 16 -1 (-2800 3650)(-2800 3600);
WIRE 16 -1 (-2975 3600)(-2800 3600);
WIRE 16 -1 (-2800 3600)(-2800 3550);
WIRE 16 -1 (-2975 3550)(-2800 3550);
WIRE 16 -1 (-2800 3550)(-2800 3500);
WIRE 16 -1 (-2975 3500)(-2800 3500);
WIRE 16 -1 (-2800 3500)(-2800 3450);
WIRE 16 -1 (-2975 3450)(-2800 3450);
WIRE 16 -1 (-2800 3450)(-2800 3400);
WIRE 16 -1 (-2975 3400)(-2800 3400);
WIRE 16 -1 (-2800 3400)(-2800 3350);
WIRE 16 -1 (-2975 3350)(-2800 3350);
WIRE 16 -1 (-2800 3350)(-2800 3300);
WIRE 16 -1 (-2975 3300)(-2800 3300);
WIRE 16 -1 (-2800 3300)(-2800 3250);
WIRE 16 -1 (-2975 3250)(-2800 3250);
WIRE 16 -1 (-2800 3250)(-2800 3200);
WIRE 16 -1 (-2975 3200)(-2800 3200);
WIRE 16 -1 (-2800 3200)(-2800 3150);
WIRE 16 -1 (-2975 3150)(-2800 3150);
WIRE 16 -1 (-2800 3150)(-2800 3100);
WIRE 16 -1 (-2975 3100)(-2800 3100);
WIRE 16 -1 (-2800 3100)(-2800 3050);
WIRE 16 -1 (-2975 3050)(-2800 3050);
WIRE 16 -1 (-2800 3050)(-2800 3000);
WIRE 16 -1 (-2975 3000)(-2800 3000);
WIRE 16 -1 (-2800 3000)(-2800 2950);
WIRE 16 -1 (-2975 2950)(-2800 2950);
WIRE 16 -1 (-2800 2950)(-2800 2900);
WIRE 16 -1 (-2975 2900)(-2800 2900);
WIRE 16 -1 (-2800 2900)(-2800 2850);
WIRE 16 -1 (-2975 2850)(-2800 2850);
WIRE 16 -1 (-2800 2850)(-2800 2800);
WIRE 16 -1 (-2975 2800)(-2800 2800);
WIRE 16 -1 (-2800 2800)(-2800 2750);
WIRE 16 -1 (-2975 2750)(-2800 2750);
WIRE 16 -1 (-2800 2750)(-2800 2700);
WIRE 16 -1 (-2975 2700)(-2800 2700);
WIRE 16 -1 (-2800 2700)(-2800 2650);
WIRE 16 -1 (-2975 2650)(-2800 2650);
WIRE 16 -1 (-2800 2650)(-2800 2600);
WIRE 16 -1 (-2975 2600)(-2800 2600);
WIRE 16 -1 (-2800 2600)(-2800 2550);
WIRE 16 -1 (-2975 2550)(-2800 2550);
WIRE 16 -1 (-2800 2550)(-2800 2500);
WIRE 16 -1 (-2975 2500)(-2800 2500);
WIRE 16 -1 (-2800 2500)(-2800 2450);
WIRE 16 -1 (-2975 2450)(-2800 2450);
WIRE 16 -1 (-2800 2450)(-2800 2400);
WIRE 16 -1 (-2975 2400)(-2800 2400);
WIRE 16 -1 (-2800 2400)(-2800 2350);
WIRE 16 -1 (-2975 2350)(-2800 2350);
WIRE 16 -1 (-2800 2350)(-2800 2300);
WIRE 16 -1 (-2975 2300)(-2800 2300);
WIRE 16 -1 (-2800 2300)(-2800 2250);
WIRE 16 -1 (-2975 2250)(-2800 2250);
WIRE 16 -1 (-2800 2250)(-2800 2200);
WIRE 16 -1 (-2975 2200)(-2800 2200);
WIRE 16 -1 (-2800 2200)(-2800 2150);
WIRE 16 -1 (-2975 2150)(-2800 2150);
WIRE 16 -1 (-2800 2150)(-2800 2100);
WIRE 16 -1 (-2975 2100)(-2800 2100);
WIRE 16 -1 (-2800 2100)(-2800 2050);
WIRE 16 -1 (-2975 2050)(-2800 2050);
WIRE 16 -1 (-2800 2050)(-2800 2000);
WIRE 16 -1 (-2975 2000)(-2800 2000);
WIRE 16 -1 (-2800 2000)(-2800 1950);
WIRE 16 -1 (-2975 1950)(-2800 1950);
WIRE 16 -1 (-2800 1950)(-2800 1900);
WIRE 16 -1 (-2975 1900)(-2800 1900);
WIRE 16 -1 (-2800 1900)(-2800 1850);
WIRE 16 -1 (-2975 1850)(-2800 1850);
WIRE 16 -1 (-2800 1850)(-2800 1800);
WIRE 16 -1 (-2975 1800)(-2800 1800);
WIRE 16 -1 (-2800 1800)(-2800 1750);
WIRE 16 -1 (-2975 1750)(-2800 1750);
WIRE 16 -1 (-2800 1750)(-2800 1700);
WIRE 16 -1 (-2975 1700)(-2800 1700);
WIRE 16 -1 (-2800 1700)(-2800 1650);
WIRE 16 -1 (-2975 1650)(-2800 1650);
WIRE 16 -1 (-2800 1650)(-2800 1600);
WIRE 16 -1 (-2975 1600)(-2800 1600);
WIRE 16 -1 (-2800 1600)(-2800 1550);
WIRE 16 -1 (-2975 1550)(-2800 1550);
WIRE 16 -1 (-2800 1550)(-2800 1500);
WIRE 16 -1 (-2975 1500)(-2800 1500);
WIRE 16 -1 (-2800 1500)(-2800 1450);
WIRE 16 -1 (-2975 1450)(-2800 1450);
WIRE 16 -1 (-2800 1450)(-2800 1400);
WIRE 16 -1 (-2975 1400)(-2800 1400);
WIRE 16 -1 (-2800 1400)(-2800 1350);
WIRE 16 -1 (-2975 1350)(-2800 1350);
WIRE 16 -1 (-2800 1350)(-2800 1300);
WIRE 16 -1 (-2975 1300)(-2800 1300);
WIRE 16 -1 (-2800 1300)(-2800 1250);
WIRE 16 -1 (-2975 1250)(-2800 1250);
WIRE 16 -1 (-2800 1250)(-2800 1200);
WIRE 16 -1 (-2975 1200)(-2800 1200);
WIRE 16 -1 (-2800 1200)(-2800 1150);
WIRE 16 -1 (-2975 1150)(-2800 1150);
WIRE 16 -1 (-2800 1150)(-2800 1100);
WIRE 16 -1 (-2975 1100)(-2800 1100);
WIRE 16 -1 (-2800 1100)(-2800 1050);
WIRE 16 -1 (-2975 1050)(-2800 1050);
WIRE 16 -1 (-2800 1050)(-2800 1000);
WIRE 16 -1 (-2975 1000)(-2800 1000);
WIRE 16 -1 (-2800 1000)(-2800 950);
WIRE 16 -1 (-2975 950)(-2800 950);
WIRE 16 -1 (-2800 950)(-2800 900);
WIRE 16 -1 (-2975 900)(-2800 900);
WIRE 16 -1 (-2800 900)(-2800 850);
WIRE 16 -1 (-2975 850)(-2800 850);
WIRE 16 -1 (-2800 850)(-2800 800);
WIRE 16 -1 (-2975 800)(-2800 800);
WIRE 16 -1 (-2800 800)(-2800 750);
WIRE 16 -1 (-2975 750)(-2800 750);
WIRE 16 -1 (-2800 750)(-2800 700);
WIRE 16 -1 (-2975 700)(-2800 700);
WIRE 16 -1 (-2800 700)(-2800 575);
WIRE 16 -1 (-1250 4600)(-1075 4600);
WIRE 16 -1 (-1075 4600)(-1075 4550);
WIRE 16 -1 (-1250 4550)(-1075 4550);
WIRE 16 -1 (-1075 4550)(-1075 4500);
WIRE 16 -1 (-1250 4500)(-1075 4500);
WIRE 16 -1 (-1075 4500)(-1075 4450);
WIRE 16 -1 (-1250 4450)(-1075 4450);
WIRE 16 -1 (-1075 4450)(-1075 4400);
WIRE 16 -1 (-1250 4400)(-1075 4400);
WIRE 16 -1 (-1075 4400)(-1075 4350);
WIRE 16 -1 (-1250 4350)(-1075 4350);
WIRE 16 -1 (-1075 4350)(-1075 4300);
WIRE 16 -1 (-1250 4300)(-1075 4300);
WIRE 16 -1 (-1075 4300)(-1075 4250);
WIRE 16 -1 (-1250 4250)(-1075 4250);
WIRE 16 -1 (-1075 4250)(-1075 4200);
WIRE 16 -1 (-1250 4200)(-1075 4200);
WIRE 16 -1 (-1075 4200)(-1075 4150);
WIRE 16 -1 (-1250 4150)(-1075 4150);
WIRE 16 -1 (-1075 4150)(-1075 4100);
WIRE 16 -1 (-1250 4100)(-1075 4100);
WIRE 16 -1 (-1075 4100)(-1075 4050);
WIRE 16 -1 (-1250 4050)(-1075 4050);
WIRE 16 -1 (-1075 4050)(-1075 4000);
WIRE 16 -1 (-1250 4000)(-1075 4000);
WIRE 16 -1 (-1075 4000)(-1075 3950);
WIRE 16 -1 (-1250 3950)(-1075 3950);
WIRE 16 -1 (-1075 3950)(-1075 3900);
WIRE 16 -1 (-1250 3900)(-1075 3900);
WIRE 16 -1 (-1075 3900)(-1075 3850);
WIRE 16 -1 (-1250 3850)(-1075 3850);
WIRE 16 -1 (-1075 3850)(-1075 3800);
WIRE 16 -1 (-1250 3800)(-1075 3800);
WIRE 16 -1 (-1075 3800)(-1075 3750);
WIRE 16 -1 (-1250 3750)(-1075 3750);
WIRE 16 -1 (-1075 3750)(-1075 3700);
WIRE 16 -1 (-1250 3700)(-1075 3700);
WIRE 16 -1 (-1075 3700)(-1075 3650);
WIRE 16 -1 (-1250 3650)(-1075 3650);
WIRE 16 -1 (-1075 3650)(-1075 3600);
WIRE 16 -1 (-1250 3600)(-1075 3600);
WIRE 16 -1 (-1075 3600)(-1075 3550);
WIRE 16 -1 (-1250 3550)(-1075 3550);
WIRE 16 -1 (-1075 3550)(-1075 3500);
WIRE 16 -1 (-1250 3500)(-1075 3500);
WIRE 16 -1 (-1075 3500)(-1075 3450);
WIRE 16 -1 (-1250 3450)(-1075 3450);
WIRE 16 -1 (-1075 3450)(-1075 3400);
WIRE 16 -1 (-1250 3400)(-1075 3400);
WIRE 16 -1 (-1075 3400)(-1075 3350);
WIRE 16 -1 (-1250 3350)(-1075 3350);
WIRE 16 -1 (-1075 3350)(-1075 3300);
WIRE 16 -1 (-1250 3300)(-1075 3300);
WIRE 16 -1 (-1075 3300)(-1075 3250);
WIRE 16 -1 (-1250 3250)(-1075 3250);
WIRE 16 -1 (-1075 3250)(-1075 3200);
WIRE 16 -1 (-1250 3200)(-1075 3200);
WIRE 16 -1 (-1075 3200)(-1075 3150);
WIRE 16 -1 (-1250 3150)(-1075 3150);
WIRE 16 -1 (-1075 3150)(-1075 3100);
WIRE 16 -1 (-1250 3100)(-1075 3100);
WIRE 16 -1 (-1075 3100)(-1075 3050);
WIRE 16 -1 (-1250 3050)(-1075 3050);
WIRE 16 -1 (-1075 3050)(-1075 3000);
WIRE 16 -1 (-1250 3000)(-1075 3000);
WIRE 16 -1 (-1075 3000)(-1075 2950);
WIRE 16 -1 (-1250 2950)(-1075 2950);
WIRE 16 -1 (-1075 2950)(-1075 2900);
WIRE 16 -1 (-1250 2900)(-1075 2900);
WIRE 16 -1 (-1075 2900)(-1075 2850);
WIRE 16 -1 (-1250 2850)(-1075 2850);
WIRE 16 -1 (-1075 2850)(-1075 2800);
WIRE 16 -1 (-1250 2800)(-1075 2800);
WIRE 16 -1 (-1075 2800)(-1075 2750);
WIRE 16 -1 (-1250 2750)(-1075 2750);
WIRE 16 -1 (-1075 2750)(-1075 2700);
WIRE 16 -1 (-1250 2700)(-1075 2700);
WIRE 16 -1 (-1075 2700)(-1075 2650);
WIRE 16 -1 (-1250 2650)(-1075 2650);
WIRE 16 -1 (-1075 2650)(-1075 2600);
WIRE 16 -1 (-1250 2600)(-1075 2600);
WIRE 16 -1 (-1075 2600)(-1075 2550);
WIRE 16 -1 (-1250 2550)(-1075 2550);
WIRE 16 -1 (-1075 2550)(-1075 2500);
WIRE 16 -1 (-1250 2500)(-1075 2500);
WIRE 16 -1 (-1075 2500)(-1075 2450);
WIRE 16 -1 (-1250 2450)(-1075 2450);
WIRE 16 -1 (-1075 2450)(-1075 2400);
WIRE 16 -1 (-1250 2400)(-1075 2400);
WIRE 16 -1 (-1075 2400)(-1075 2350);
WIRE 16 -1 (-1250 2350)(-1075 2350);
WIRE 16 -1 (-1075 2350)(-1075 2300);
WIRE 16 -1 (-1250 2300)(-1075 2300);
WIRE 16 -1 (-1075 2300)(-1075 2250);
WIRE 16 -1 (-1250 2250)(-1075 2250);
WIRE 16 -1 (-1075 2250)(-1075 2200);
WIRE 16 -1 (-1250 2200)(-1075 2200);
WIRE 16 -1 (-1075 2200)(-1075 2150);
WIRE 16 -1 (-1250 2150)(-1075 2150);
WIRE 16 -1 (-1075 2150)(-1075 2100);
WIRE 16 -1 (-1250 2100)(-1075 2100);
WIRE 16 -1 (-1075 2100)(-1075 2050);
WIRE 16 -1 (-1250 2050)(-1075 2050);
WIRE 16 -1 (-1075 2050)(-1075 2000);
WIRE 16 -1 (-1250 2000)(-1075 2000);
WIRE 16 -1 (-1075 2000)(-1075 1950);
WIRE 16 -1 (-1250 1950)(-1075 1950);
WIRE 16 -1 (-1075 1950)(-1075 1900);
WIRE 16 -1 (-1250 1900)(-1075 1900);
WIRE 16 -1 (-1075 1900)(-1075 1850);
WIRE 16 -1 (-1250 1850)(-1075 1850);
WIRE 16 -1 (-1075 1850)(-1075 1800);
WIRE 16 -1 (-1250 1800)(-1075 1800);
WIRE 16 -1 (-1075 1800)(-1075 1750);
WIRE 16 -1 (-1250 1750)(-1075 1750);
WIRE 16 -1 (-1075 1750)(-1075 1700);
WIRE 16 -1 (-1250 1700)(-1075 1700);
WIRE 16 -1 (-1075 1700)(-1075 1650);
WIRE 16 -1 (-1250 1650)(-1075 1650);
WIRE 16 -1 (-1075 1650)(-1075 1600);
WIRE 16 -1 (-1250 1600)(-1075 1600);
WIRE 16 -1 (-1075 1600)(-1075 1550);
WIRE 16 -1 (-1250 1550)(-1075 1550);
WIRE 16 -1 (-1075 1550)(-1075 1500);
WIRE 16 -1 (-1250 1500)(-1075 1500);
WIRE 16 -1 (-1075 1500)(-1075 1450);
WIRE 16 -1 (-1250 1450)(-1075 1450);
WIRE 16 -1 (-1075 1450)(-1075 1400);
WIRE 16 -1 (-1250 1400)(-1075 1400);
WIRE 16 -1 (-1075 1400)(-1075 1350);
WIRE 16 -1 (-1250 1350)(-1075 1350);
WIRE 16 -1 (-1075 1350)(-1075 1300);
WIRE 16 -1 (-1250 1300)(-1075 1300);
WIRE 16 -1 (-1075 1300)(-1075 1250);
WIRE 16 -1 (-1250 1250)(-1075 1250);
WIRE 16 -1 (-1075 1250)(-1075 1200);
WIRE 16 -1 (-1250 1200)(-1075 1200);
WIRE 16 -1 (-1075 1200)(-1075 1150);
WIRE 16 -1 (-1250 1150)(-1075 1150);
WIRE 16 -1 (-1075 1150)(-1075 1100);
WIRE 16 -1 (-1250 1100)(-1075 1100);
WIRE 16 -1 (-1075 1100)(-1075 1050);
WIRE 16 -1 (-1250 1050)(-1075 1050);
WIRE 16 -1 (-1075 1050)(-1075 1000);
WIRE 16 -1 (-1250 1000)(-1075 1000);
WIRE 16 -1 (-1075 1000)(-1075 950);
WIRE 16 -1 (-1250 950)(-1075 950);
WIRE 16 -1 (-1075 950)(-1075 900);
WIRE 16 -1 (-1250 900)(-1075 900);
WIRE 16 -1 (-1075 900)(-1075 850);
WIRE 16 -1 (-1250 850)(-1075 850);
WIRE 16 -1 (-1075 850)(-1075 800);
WIRE 16 -1 (-1250 800)(-1075 800);
WIRE 16 -1 (-1075 800)(-1075 750);
WIRE 16 -1 (-1250 750)(-1075 750);
WIRE 16 -1 (-1075 750)(-1075 700);
WIRE 16 -1 (-1250 700)(-1075 700);
WIRE 16 -1 (-1075 700)(-1075 650);
WIRE 16 -1 (-1250 650)(-1075 650);
WIRE 16 -1 (-1075 650)(-1075 525);
WIRE 16 -1 (-5875 4650)(-6025 4650);
WIRE 16 -1 (-6025 4650)(-6025 4600);
WIRE 16 -1 (-5875 4600)(-6025 4600);
WIRE 16 -1 (-6025 4600)(-6025 4550);
WIRE 16 -1 (-5875 4550)(-6025 4550);
WIRE 16 -1 (-6025 4550)(-6025 4500);
WIRE 16 -1 (-5875 4500)(-6025 4500);
WIRE 16 -1 (-6025 4500)(-6025 4450);
WIRE 16 -1 (-5875 4450)(-6025 4450);
WIRE 16 -1 (-6025 4450)(-6025 4400);
WIRE 16 -1 (-5875 4400)(-6025 4400);
WIRE 16 -1 (-6025 4400)(-6025 4350);
WIRE 16 -1 (-5875 4350)(-6025 4350);
WIRE 16 -1 (-6025 4350)(-6025 4300);
WIRE 16 -1 (-5875 4300)(-6025 4300);
WIRE 16 -1 (-6025 4300)(-6025 4250);
WIRE 16 -1 (-5875 4250)(-6025 4250);
WIRE 16 -1 (-6025 4250)(-6025 4200);
WIRE 16 -1 (-5875 4200)(-6025 4200);
WIRE 16 -1 (-6025 4200)(-6025 4150);
WIRE 16 -1 (-5875 4150)(-6025 4150);
WIRE 16 -1 (-6025 4150)(-6025 4100);
WIRE 16 -1 (-5875 4100)(-6025 4100);
WIRE 16 -1 (-6025 4100)(-6025 4050);
WIRE 16 -1 (-5875 4050)(-6025 4050);
WIRE 16 -1 (-6025 4050)(-6025 4000);
WIRE 16 -1 (-5875 4000)(-6025 4000);
WIRE 16 -1 (-6025 4000)(-6025 3950);
WIRE 16 -1 (-5875 3950)(-6025 3950);
WIRE 16 -1 (-6025 3950)(-6025 3900);
WIRE 16 -1 (-5875 3900)(-6025 3900);
WIRE 16 -1 (-6025 3900)(-6025 3850);
WIRE 16 -1 (-5875 3850)(-6025 3850);
WIRE 16 -1 (-6025 3850)(-6025 3800);
WIRE 16 -1 (-5875 3800)(-6025 3800);
WIRE 16 -1 (-6025 3800)(-6025 3750);
WIRE 16 -1 (-5875 3750)(-6025 3750);
WIRE 16 -1 (-6025 3750)(-6025 3700);
WIRE 16 -1 (-5875 3700)(-6025 3700);
WIRE 16 -1 (-6025 3700)(-6025 3650);
WIRE 16 -1 (-5875 3650)(-6025 3650);
WIRE 16 -1 (-6025 3650)(-6025 3600);
WIRE 16 -1 (-5875 3600)(-6025 3600);
WIRE 16 -1 (-6025 3600)(-6025 3550);
WIRE 16 -1 (-5875 3550)(-6025 3550);
WIRE 16 -1 (-6025 3550)(-6025 3500);
WIRE 16 -1 (-5875 3500)(-6025 3500);
WIRE 16 -1 (-6025 3500)(-6025 3450);
WIRE 16 -1 (-5875 3450)(-6025 3450);
WIRE 16 -1 (-6025 3450)(-6025 3400);
WIRE 16 -1 (-5875 3400)(-6025 3400);
WIRE 16 -1 (-6025 3400)(-6025 3350);
WIRE 16 -1 (-5875 3350)(-6025 3350);
WIRE 16 -1 (-6025 3350)(-6025 3300);
WIRE 16 -1 (-5875 3300)(-6025 3300);
WIRE 16 -1 (-6025 3300)(-6025 3250);
WIRE 16 -1 (-5875 3250)(-6025 3250);
WIRE 16 -1 (-6025 3250)(-6025 3200);
WIRE 16 -1 (-5875 3200)(-6025 3200);
WIRE 16 -1 (-6025 3200)(-6025 3150);
WIRE 16 -1 (-5875 3150)(-6025 3150);
WIRE 16 -1 (-6025 3150)(-6025 3100);
WIRE 16 -1 (-5875 3100)(-6025 3100);
WIRE 16 -1 (-6025 3100)(-6025 3050);
WIRE 16 -1 (-5875 3050)(-6025 3050);
WIRE 16 -1 (-6025 3050)(-6025 3000);
WIRE 16 -1 (-5875 3000)(-6025 3000);
WIRE 16 -1 (-6025 3000)(-6025 2950);
WIRE 16 -1 (-5875 2950)(-6025 2950);
WIRE 16 -1 (-6025 2950)(-6025 2900);
WIRE 16 -1 (-5875 2900)(-6025 2900);
WIRE 16 -1 (-6025 2900)(-6025 2850);
WIRE 16 -1 (-5875 2850)(-6025 2850);
WIRE 16 -1 (-6025 2850)(-6025 2800);
WIRE 16 -1 (-5875 2800)(-6025 2800);
WIRE 16 -1 (-6025 2800)(-6025 2750);
WIRE 16 -1 (-5875 2750)(-6025 2750);
WIRE 16 -1 (-6025 2750)(-6025 2700);
WIRE 16 -1 (-5875 2700)(-6025 2700);
WIRE 16 -1 (-6025 2700)(-6025 2650);
WIRE 16 -1 (-5875 2650)(-6025 2650);
WIRE 16 -1 (-6025 2650)(-6025 2600);
WIRE 16 -1 (-5875 2600)(-6025 2600);
WIRE 16 -1 (-6025 2600)(-6025 2550);
WIRE 16 -1 (-5875 2550)(-6025 2550);
WIRE 16 -1 (-6025 2550)(-6025 2500);
WIRE 16 -1 (-5875 2500)(-6025 2500);
WIRE 16 -1 (-6025 2500)(-6025 2450);
WIRE 16 -1 (-5875 2450)(-6025 2450);
WIRE 16 -1 (-6025 2450)(-6025 2400);
WIRE 16 -1 (-5875 2400)(-6025 2400);
WIRE 16 -1 (-6025 2400)(-6025 2350);
WIRE 16 -1 (-5875 2350)(-6025 2350);
WIRE 16 -1 (-6025 2350)(-6025 2300);
WIRE 16 -1 (-5875 2300)(-6025 2300);
WIRE 16 -1 (-6025 2300)(-6025 2250);
WIRE 16 -1 (-5875 2250)(-6025 2250);
WIRE 16 -1 (-6025 2250)(-6025 2200);
WIRE 16 -1 (-5875 2200)(-6025 2200);
WIRE 16 -1 (-6025 2200)(-6025 2150);
WIRE 16 -1 (-5875 2150)(-6025 2150);
WIRE 16 -1 (-6025 2150)(-6025 2100);
WIRE 16 -1 (-5875 2100)(-6025 2100);
WIRE 16 -1 (-6025 2100)(-6025 2050);
WIRE 16 -1 (-5875 2050)(-6025 2050);
WIRE 16 -1 (-6025 2050)(-6025 2000);
WIRE 16 -1 (-5875 2000)(-6025 2000);
WIRE 16 -1 (-6025 2000)(-6025 1950);
WIRE 16 -1 (-5875 1950)(-6025 1950);
WIRE 16 -1 (-6025 1950)(-6025 1900);
WIRE 16 -1 (-5875 1900)(-6025 1900);
WIRE 16 -1 (-6025 1900)(-6025 1850);
WIRE 16 -1 (-5875 1850)(-6025 1850);
WIRE 16 -1 (-6025 1850)(-6025 1800);
WIRE 16 -1 (-5875 1800)(-6025 1800);
WIRE 16 -1 (-6025 1800)(-6025 1750);
WIRE 16 -1 (-5875 1750)(-6025 1750);
WIRE 16 -1 (-6025 1750)(-6025 1700);
WIRE 16 -1 (-5875 1700)(-6025 1700);
WIRE 16 -1 (-6025 1700)(-6025 1650);
WIRE 16 -1 (-5875 1650)(-6025 1650);
WIRE 16 -1 (-6025 1650)(-6025 1600);
WIRE 16 -1 (-5875 1600)(-6025 1600);
WIRE 16 -1 (-6025 1600)(-6025 1550);
WIRE 16 -1 (-5875 1550)(-6025 1550);
WIRE 16 -1 (-6025 1550)(-6025 1500);
WIRE 16 -1 (-5875 1500)(-6025 1500);
WIRE 16 -1 (-6025 1500)(-6025 1450);
WIRE 16 -1 (-5875 1450)(-6025 1450);
WIRE 16 -1 (-6025 1450)(-6025 1400);
WIRE 16 -1 (-5875 1400)(-6025 1400);
WIRE 16 -1 (-6025 1400)(-6025 1350);
WIRE 16 -1 (-5875 1350)(-6025 1350);
WIRE 16 -1 (-6025 1350)(-6025 1300);
WIRE 16 -1 (-5875 1300)(-6025 1300);
WIRE 16 -1 (-6025 1300)(-6025 1250);
WIRE 16 -1 (-5875 1250)(-6025 1250);
WIRE 16 -1 (-6025 1250)(-6025 1200);
WIRE 16 -1 (-5875 1200)(-6025 1200);
WIRE 16 -1 (-6025 1200)(-6025 1150);
WIRE 16 -1 (-5875 1150)(-6025 1150);
WIRE 16 -1 (-6025 1150)(-6025 1100);
WIRE 16 -1 (-5875 1100)(-6025 1100);
WIRE 16 -1 (-6025 1100)(-6025 1050);
WIRE 16 -1 (-5875 1050)(-6025 1050);
WIRE 16 -1 (-6025 1050)(-6025 1000);
WIRE 16 -1 (-5875 1000)(-6025 1000);
WIRE 16 -1 (-6025 1000)(-6025 950);
WIRE 16 -1 (-5875 950)(-6025 950);
WIRE 16 -1 (-6025 950)(-6025 900);
WIRE 16 -1 (-6025 900)(-5875 900);
WIRE 16 -1 (-6025 900)(-6025 850);
WIRE 16 -1 (-5875 850)(-6025 850);
WIRE 16 -1 (-6025 850)(-6025 800);
WIRE 16 -1 (-5875 800)(-6025 800);
WIRE 16 -1 (-6025 800)(-6025 750);
WIRE 16 -1 (-5875 750)(-6025 750);
WIRE 16 -1 (-6025 750)(-6025 700);
WIRE 16 -1 (-6025 700)(-5875 700);
WIRE 16 -1 (-6025 700)(-6025 600);
WIRE 16 -1 (-4175 4650)(-4350 4650);
WIRE 16 -1 (-4350 4650)(-4350 4600);
WIRE 16 -1 (-4175 4600)(-4350 4600);
WIRE 16 -1 (-4350 4600)(-4350 4550);
WIRE 16 -1 (-4175 4550)(-4350 4550);
WIRE 16 -1 (-4350 4550)(-4350 4500);
WIRE 16 -1 (-4175 4500)(-4350 4500);
WIRE 16 -1 (-4350 4500)(-4350 4450);
WIRE 16 -1 (-4175 4450)(-4350 4450);
WIRE 16 -1 (-4350 4450)(-4350 4400);
WIRE 16 -1 (-4175 4400)(-4350 4400);
WIRE 16 -1 (-4350 4400)(-4350 4350);
WIRE 16 -1 (-4175 4350)(-4350 4350);
WIRE 16 -1 (-4350 4350)(-4350 4300);
WIRE 16 -1 (-4175 4300)(-4350 4300);
WIRE 16 -1 (-4350 4300)(-4350 4250);
WIRE 16 -1 (-4175 4250)(-4350 4250);
WIRE 16 -1 (-4350 4250)(-4350 4200);
WIRE 16 -1 (-4175 4200)(-4350 4200);
WIRE 16 -1 (-4350 4200)(-4350 4150);
WIRE 16 -1 (-4175 4150)(-4350 4150);
WIRE 16 -1 (-4350 4150)(-4350 4100);
WIRE 16 -1 (-4175 4100)(-4350 4100);
WIRE 16 -1 (-4350 4100)(-4350 4050);
WIRE 16 -1 (-4175 4050)(-4350 4050);
WIRE 16 -1 (-4350 4050)(-4350 4000);
WIRE 16 -1 (-4175 4000)(-4350 4000);
WIRE 16 -1 (-4350 4000)(-4350 3950);
WIRE 16 -1 (-4175 3950)(-4350 3950);
WIRE 16 -1 (-4350 3950)(-4350 3900);
WIRE 16 -1 (-4175 3900)(-4350 3900);
WIRE 16 -1 (-4350 3900)(-4350 3850);
WIRE 16 -1 (-4175 3850)(-4350 3850);
WIRE 16 -1 (-4350 3850)(-4350 3800);
WIRE 16 -1 (-4175 3800)(-4350 3800);
WIRE 16 -1 (-4350 3800)(-4350 3750);
WIRE 16 -1 (-4175 3750)(-4350 3750);
WIRE 16 -1 (-4350 3750)(-4350 3700);
WIRE 16 -1 (-4175 3700)(-4350 3700);
WIRE 16 -1 (-4350 3700)(-4350 3650);
WIRE 16 -1 (-4175 3650)(-4350 3650);
WIRE 16 -1 (-4350 3650)(-4350 3600);
WIRE 16 -1 (-4175 3600)(-4350 3600);
WIRE 16 -1 (-4350 3600)(-4350 3550);
WIRE 16 -1 (-4175 3550)(-4350 3550);
WIRE 16 -1 (-4350 3550)(-4350 3500);
WIRE 16 -1 (-4175 3500)(-4350 3500);
WIRE 16 -1 (-4350 3500)(-4350 3450);
WIRE 16 -1 (-4175 3450)(-4350 3450);
WIRE 16 -1 (-4350 3450)(-4350 3400);
WIRE 16 -1 (-4175 3400)(-4350 3400);
WIRE 16 -1 (-4350 3400)(-4350 3350);
WIRE 16 -1 (-4175 3350)(-4350 3350);
WIRE 16 -1 (-4350 3350)(-4350 3300);
WIRE 16 -1 (-4175 3300)(-4350 3300);
WIRE 16 -1 (-4350 3300)(-4350 3250);
WIRE 16 -1 (-4175 3250)(-4350 3250);
WIRE 16 -1 (-4350 3250)(-4350 3200);
WIRE 16 -1 (-4175 3200)(-4350 3200);
WIRE 16 -1 (-4350 3200)(-4350 3150);
WIRE 16 -1 (-4175 3150)(-4350 3150);
WIRE 16 -1 (-4350 3150)(-4350 3100);
WIRE 16 -1 (-4175 3100)(-4350 3100);
WIRE 16 -1 (-4350 3100)(-4350 3050);
WIRE 16 -1 (-4175 3050)(-4350 3050);
WIRE 16 -1 (-4350 3050)(-4350 3000);
WIRE 16 -1 (-4175 3000)(-4350 3000);
WIRE 16 -1 (-4350 3000)(-4350 2950);
WIRE 16 -1 (-4175 2950)(-4350 2950);
WIRE 16 -1 (-4350 2950)(-4350 2900);
WIRE 16 -1 (-4175 2900)(-4350 2900);
WIRE 16 -1 (-4350 2900)(-4350 2850);
WIRE 16 -1 (-4175 2850)(-4350 2850);
WIRE 16 -1 (-4350 2850)(-4350 2800);
WIRE 16 -1 (-4175 2800)(-4350 2800);
WIRE 16 -1 (-4350 2800)(-4350 2750);
WIRE 16 -1 (-4175 2750)(-4350 2750);
WIRE 16 -1 (-4350 2750)(-4350 2700);
WIRE 16 -1 (-4175 2700)(-4350 2700);
WIRE 16 -1 (-4350 2700)(-4350 2650);
WIRE 16 -1 (-4175 2650)(-4350 2650);
WIRE 16 -1 (-4350 2650)(-4350 2600);
WIRE 16 -1 (-4175 2600)(-4350 2600);
WIRE 16 -1 (-4350 2600)(-4350 2550);
WIRE 16 -1 (-4175 2550)(-4350 2550);
WIRE 16 -1 (-4350 2550)(-4350 2500);
WIRE 16 -1 (-4175 2500)(-4350 2500);
WIRE 16 -1 (-4350 2500)(-4350 2450);
WIRE 16 -1 (-4175 2450)(-4350 2450);
WIRE 16 -1 (-4350 2450)(-4350 2400);
WIRE 16 -1 (-4175 2400)(-4350 2400);
WIRE 16 -1 (-4350 2400)(-4350 2350);
WIRE 16 -1 (-4175 2350)(-4350 2350);
WIRE 16 -1 (-4350 2350)(-4350 2300);
WIRE 16 -1 (-4175 2300)(-4350 2300);
WIRE 16 -1 (-4350 2300)(-4350 2250);
WIRE 16 -1 (-4175 2250)(-4350 2250);
WIRE 16 -1 (-4350 2250)(-4350 2200);
WIRE 16 -1 (-4175 2200)(-4350 2200);
WIRE 16 -1 (-4350 2200)(-4350 2150);
WIRE 16 -1 (-4175 2150)(-4350 2150);
WIRE 16 -1 (-4350 2150)(-4350 2100);
WIRE 16 -1 (-4175 2100)(-4350 2100);
WIRE 16 -1 (-4350 2100)(-4350 2050);
WIRE 16 -1 (-4175 2050)(-4350 2050);
WIRE 16 -1 (-4350 2050)(-4350 2000);
WIRE 16 -1 (-4175 2000)(-4350 2000);
WIRE 16 -1 (-4350 2000)(-4350 1950);
WIRE 16 -1 (-4175 1950)(-4350 1950);
WIRE 16 -1 (-4350 1950)(-4350 1900);
WIRE 16 -1 (-4175 1900)(-4350 1900);
WIRE 16 -1 (-4350 1900)(-4350 1850);
WIRE 16 -1 (-4175 1850)(-4350 1850);
WIRE 16 -1 (-4350 1850)(-4350 1800);
WIRE 16 -1 (-4175 1800)(-4350 1800);
WIRE 16 -1 (-4350 1800)(-4350 1750);
WIRE 16 -1 (-4175 1750)(-4350 1750);
WIRE 16 -1 (-4350 1750)(-4350 1700);
WIRE 16 -1 (-4175 1700)(-4350 1700);
WIRE 16 -1 (-4350 1700)(-4350 1650);
WIRE 16 -1 (-4175 1650)(-4350 1650);
WIRE 16 -1 (-4350 1650)(-4350 1600);
WIRE 16 -1 (-4175 1600)(-4350 1600);
WIRE 16 -1 (-4350 1600)(-4350 1550);
WIRE 16 -1 (-4175 1550)(-4350 1550);
WIRE 16 -1 (-4350 1550)(-4350 1500);
WIRE 16 -1 (-4175 1500)(-4350 1500);
WIRE 16 -1 (-4350 1500)(-4350 1450);
WIRE 16 -1 (-4175 1450)(-4350 1450);
WIRE 16 -1 (-4350 1450)(-4350 1400);
WIRE 16 -1 (-4175 1400)(-4350 1400);
WIRE 16 -1 (-4350 1400)(-4350 1350);
WIRE 16 -1 (-4175 1350)(-4350 1350);
WIRE 16 -1 (-4350 1350)(-4350 1300);
WIRE 16 -1 (-4175 1300)(-4350 1300);
WIRE 16 -1 (-4350 1300)(-4350 1250);
WIRE 16 -1 (-4175 1250)(-4350 1250);
WIRE 16 -1 (-4350 1250)(-4350 1200);
WIRE 16 -1 (-4175 1200)(-4350 1200);
WIRE 16 -1 (-4350 1200)(-4350 1150);
WIRE 16 -1 (-4175 1150)(-4350 1150);
WIRE 16 -1 (-4350 1150)(-4350 1100);
WIRE 16 -1 (-4175 1100)(-4350 1100);
WIRE 16 -1 (-4350 1100)(-4350 1050);
WIRE 16 -1 (-4175 1050)(-4350 1050);
WIRE 16 -1 (-4350 1050)(-4350 1000);
WIRE 16 -1 (-4175 1000)(-4350 1000);
WIRE 16 -1 (-4350 1000)(-4350 950);
WIRE 16 -1 (-4175 950)(-4350 950);
WIRE 16 -1 (-4350 950)(-4350 900);
WIRE 16 -1 (-4350 900)(-4175 900);
WIRE 16 -1 (-4350 900)(-4350 850);
WIRE 16 -1 (-4175 850)(-4350 850);
WIRE 16 -1 (-4350 850)(-4350 800);
WIRE 16 -1 (-4175 800)(-4350 800);
WIRE 16 -1 (-4350 800)(-4350 750);
WIRE 16 -1 (-4175 750)(-4350 750);
WIRE 16 -1 (-4350 750)(-4350 700);
WIRE 16 -1 (-4350 700)(-4175 700);
WIRE 16 -1 (-4350 700)(-4350 600);
WIRE 16 -1 (-2450 4600)(-2625 4600);
WIRE 16 -1 (-2625 4600)(-2625 4550);
WIRE 16 -1 (-2450 4550)(-2625 4550);
WIRE 16 -1 (-2625 4550)(-2625 4500);
WIRE 16 -1 (-2450 4500)(-2625 4500);
WIRE 16 -1 (-2625 4500)(-2625 4450);
WIRE 16 -1 (-2450 4450)(-2625 4450);
WIRE 16 -1 (-2625 4450)(-2625 4400);
WIRE 16 -1 (-2450 4400)(-2625 4400);
WIRE 16 -1 (-2625 4400)(-2625 4350);
WIRE 16 -1 (-2450 4350)(-2625 4350);
WIRE 16 -1 (-2625 4350)(-2625 4300);
WIRE 16 -1 (-2450 4300)(-2625 4300);
WIRE 16 -1 (-2625 4300)(-2625 4250);
WIRE 16 -1 (-2450 4250)(-2625 4250);
WIRE 16 -1 (-2625 4250)(-2625 4200);
WIRE 16 -1 (-2450 4200)(-2625 4200);
WIRE 16 -1 (-2625 4200)(-2625 4150);
WIRE 16 -1 (-2450 4150)(-2625 4150);
WIRE 16 -1 (-2625 4150)(-2625 4100);
WIRE 16 -1 (-2450 4100)(-2625 4100);
WIRE 16 -1 (-2625 4100)(-2625 4050);
WIRE 16 -1 (-2450 4050)(-2625 4050);
WIRE 16 -1 (-2625 4050)(-2625 4000);
WIRE 16 -1 (-2450 4000)(-2625 4000);
WIRE 16 -1 (-2625 4000)(-2625 3950);
WIRE 16 -1 (-2450 3950)(-2625 3950);
WIRE 16 -1 (-2625 3950)(-2625 3900);
WIRE 16 -1 (-2450 3900)(-2625 3900);
WIRE 16 -1 (-2625 3900)(-2625 3850);
WIRE 16 -1 (-2450 3850)(-2625 3850);
WIRE 16 -1 (-2625 3850)(-2625 3800);
WIRE 16 -1 (-2450 3800)(-2625 3800);
WIRE 16 -1 (-2625 3800)(-2625 3750);
WIRE 16 -1 (-2450 3750)(-2625 3750);
WIRE 16 -1 (-2625 3750)(-2625 3700);
WIRE 16 -1 (-2450 3700)(-2625 3700);
WIRE 16 -1 (-2625 3700)(-2625 3650);
WIRE 16 -1 (-2450 3650)(-2625 3650);
WIRE 16 -1 (-2625 3650)(-2625 3600);
WIRE 16 -1 (-2450 3600)(-2625 3600);
WIRE 16 -1 (-2625 3600)(-2625 3550);
WIRE 16 -1 (-2450 3550)(-2625 3550);
WIRE 16 -1 (-2625 3550)(-2625 3500);
WIRE 16 -1 (-2450 3500)(-2625 3500);
WIRE 16 -1 (-2625 3500)(-2625 3450);
WIRE 16 -1 (-2450 3450)(-2625 3450);
WIRE 16 -1 (-2625 3450)(-2625 3400);
WIRE 16 -1 (-2450 3400)(-2625 3400);
WIRE 16 -1 (-2625 3400)(-2625 3350);
WIRE 16 -1 (-2450 3350)(-2625 3350);
WIRE 16 -1 (-2625 3350)(-2625 3300);
WIRE 16 -1 (-2450 3300)(-2625 3300);
WIRE 16 -1 (-2625 3300)(-2625 3250);
WIRE 16 -1 (-2450 3250)(-2625 3250);
WIRE 16 -1 (-2625 3250)(-2625 3200);
WIRE 16 -1 (-2450 3200)(-2625 3200);
WIRE 16 -1 (-2625 3200)(-2625 3150);
WIRE 16 -1 (-2450 3150)(-2625 3150);
WIRE 16 -1 (-2625 3150)(-2625 3100);
WIRE 16 -1 (-2450 3100)(-2625 3100);
WIRE 16 -1 (-2625 3100)(-2625 3050);
WIRE 16 -1 (-2450 3050)(-2625 3050);
WIRE 16 -1 (-2625 3050)(-2625 3000);
WIRE 16 -1 (-2450 3000)(-2625 3000);
WIRE 16 -1 (-2625 3000)(-2625 2950);
WIRE 16 -1 (-2450 2950)(-2625 2950);
WIRE 16 -1 (-2625 2950)(-2625 2900);
WIRE 16 -1 (-2450 2900)(-2625 2900);
WIRE 16 -1 (-2625 2900)(-2625 2850);
WIRE 16 -1 (-2450 2850)(-2625 2850);
WIRE 16 -1 (-2625 2850)(-2625 2800);
WIRE 16 -1 (-2450 2800)(-2625 2800);
WIRE 16 -1 (-2625 2800)(-2625 2750);
WIRE 16 -1 (-2450 2750)(-2625 2750);
WIRE 16 -1 (-2625 2750)(-2625 2700);
WIRE 16 -1 (-2450 2700)(-2625 2700);
WIRE 16 -1 (-2625 2700)(-2625 2650);
WIRE 16 -1 (-2450 2650)(-2625 2650);
WIRE 16 -1 (-2625 2650)(-2625 2600);
WIRE 16 -1 (-2450 2600)(-2625 2600);
WIRE 16 -1 (-2625 2600)(-2625 2550);
WIRE 16 -1 (-2450 2550)(-2625 2550);
WIRE 16 -1 (-2625 2550)(-2625 2500);
WIRE 16 -1 (-2450 2500)(-2625 2500);
WIRE 16 -1 (-2625 2500)(-2625 2450);
WIRE 16 -1 (-2450 2450)(-2625 2450);
WIRE 16 -1 (-2625 2450)(-2625 2400);
WIRE 16 -1 (-2450 2400)(-2625 2400);
WIRE 16 -1 (-2625 2400)(-2625 2350);
WIRE 16 -1 (-2450 2350)(-2625 2350);
WIRE 16 -1 (-2625 2350)(-2625 2300);
WIRE 16 -1 (-2450 2300)(-2625 2300);
WIRE 16 -1 (-2625 2300)(-2625 2250);
WIRE 16 -1 (-2450 2250)(-2625 2250);
WIRE 16 -1 (-2625 2250)(-2625 2200);
WIRE 16 -1 (-2450 2200)(-2625 2200);
WIRE 16 -1 (-2625 2200)(-2625 2150);
WIRE 16 -1 (-2450 2150)(-2625 2150);
WIRE 16 -1 (-2625 2150)(-2625 2100);
WIRE 16 -1 (-2450 2100)(-2625 2100);
WIRE 16 -1 (-2625 2100)(-2625 2050);
WIRE 16 -1 (-2450 2050)(-2625 2050);
WIRE 16 -1 (-2625 2050)(-2625 2000);
WIRE 16 -1 (-2450 2000)(-2625 2000);
WIRE 16 -1 (-2625 2000)(-2625 1950);
WIRE 16 -1 (-2450 1950)(-2625 1950);
WIRE 16 -1 (-2625 1950)(-2625 1900);
WIRE 16 -1 (-2450 1900)(-2625 1900);
WIRE 16 -1 (-2625 1900)(-2625 1850);
WIRE 16 -1 (-2450 1850)(-2625 1850);
WIRE 16 -1 (-2625 1850)(-2625 1800);
WIRE 16 -1 (-2450 1800)(-2625 1800);
WIRE 16 -1 (-2625 1800)(-2625 1750);
WIRE 16 -1 (-2450 1750)(-2625 1750);
WIRE 16 -1 (-2625 1750)(-2625 1700);
WIRE 16 -1 (-2450 1700)(-2625 1700);
WIRE 16 -1 (-2625 1700)(-2625 1650);
WIRE 16 -1 (-2450 1650)(-2625 1650);
WIRE 16 -1 (-2625 1650)(-2625 1600);
WIRE 16 -1 (-2450 1600)(-2625 1600);
WIRE 16 -1 (-2625 1600)(-2625 1550);
WIRE 16 -1 (-2450 1550)(-2625 1550);
WIRE 16 -1 (-2625 1550)(-2625 1500);
WIRE 16 -1 (-2450 1500)(-2625 1500);
WIRE 16 -1 (-2625 1500)(-2625 1450);
WIRE 16 -1 (-2450 1450)(-2625 1450);
WIRE 16 -1 (-2625 1450)(-2625 1400);
WIRE 16 -1 (-2450 1400)(-2625 1400);
WIRE 16 -1 (-2625 1400)(-2625 1350);
WIRE 16 -1 (-2450 1350)(-2625 1350);
WIRE 16 -1 (-2625 1350)(-2625 1300);
WIRE 16 -1 (-2450 1300)(-2625 1300);
WIRE 16 -1 (-2625 1300)(-2625 1250);
WIRE 16 -1 (-2450 1250)(-2625 1250);
WIRE 16 -1 (-2625 1250)(-2625 1200);
WIRE 16 -1 (-2450 1200)(-2625 1200);
WIRE 16 -1 (-2625 1200)(-2625 1150);
WIRE 16 -1 (-2450 1150)(-2625 1150);
WIRE 16 -1 (-2625 1150)(-2625 1100);
WIRE 16 -1 (-2450 1100)(-2625 1100);
WIRE 16 -1 (-2625 1100)(-2625 1050);
WIRE 16 -1 (-2450 1050)(-2625 1050);
WIRE 16 -1 (-2625 1050)(-2625 1000);
WIRE 16 -1 (-2450 1000)(-2625 1000);
WIRE 16 -1 (-2625 1000)(-2625 950);
WIRE 16 -1 (-2450 950)(-2625 950);
WIRE 16 -1 (-2625 950)(-2625 900);
WIRE 16 -1 (-2450 900)(-2625 900);
WIRE 16 -1 (-2625 900)(-2625 850);
WIRE 16 -1 (-2625 850)(-2450 850);
WIRE 16 -1 (-2625 850)(-2625 800);
WIRE 16 -1 (-2450 800)(-2625 800);
WIRE 16 -1 (-2625 800)(-2625 750);
WIRE 16 -1 (-2450 750)(-2625 750);
WIRE 16 -1 (-2625 750)(-2625 700);
WIRE 16 -1 (-2450 700)(-2625 700);
WIRE 16 -1 (-2625 700)(-2625 650);
WIRE 16 -1 (-2625 650)(-2450 650);
WIRE 16 -1 (-2625 650)(-2625 550);
WIRE 16 -1 (-775 4650)(-925 4650);
WIRE 16 -1 (-925 4650)(-925 4600);
WIRE 16 -1 (-775 4600)(-925 4600);
WIRE 16 -1 (-925 4550)(-925 4600);
WIRE 16 -1 (-775 4550)(-925 4550);
WIRE 16 -1 (-925 4500)(-925 4550);
WIRE 16 -1 (-775 4500)(-925 4500);
WIRE 16 -1 (-925 4450)(-925 4500);
WIRE 16 -1 (-775 4450)(-925 4450);
WIRE 16 -1 (-925 4400)(-925 4450);
WIRE 16 -1 (-775 4400)(-925 4400);
WIRE 16 -1 (-925 4350)(-925 4400);
WIRE 16 -1 (-775 4350)(-925 4350);
WIRE 16 -1 (-925 4300)(-925 4350);
WIRE 16 -1 (-775 4300)(-925 4300);
WIRE 16 -1 (-925 4250)(-925 4300);
WIRE 16 -1 (-775 4250)(-925 4250);
WIRE 16 -1 (-925 4200)(-925 4250);
WIRE 16 -1 (-775 4200)(-925 4200);
WIRE 16 -1 (-925 4150)(-925 4200);
WIRE 16 -1 (-775 4150)(-925 4150);
WIRE 16 -1 (-925 4100)(-925 4150);
WIRE 16 -1 (-775 4100)(-925 4100);
WIRE 16 -1 (-925 4050)(-925 4100);
WIRE 16 -1 (-775 4050)(-925 4050);
WIRE 16 -1 (-925 4000)(-925 4050);
WIRE 16 -1 (-775 4000)(-925 4000);
WIRE 16 -1 (-925 3950)(-925 4000);
WIRE 16 -1 (-775 3950)(-925 3950);
WIRE 16 -1 (-925 3900)(-925 3950);
WIRE 16 -1 (-775 3900)(-925 3900);
WIRE 16 -1 (-925 3850)(-925 3900);
WIRE 16 -1 (-775 3850)(-925 3850);
WIRE 16 -1 (-925 3800)(-925 3850);
WIRE 16 -1 (-775 3800)(-925 3800);
WIRE 16 -1 (-925 3750)(-925 3800);
WIRE 16 -1 (-775 3750)(-925 3750);
WIRE 16 -1 (-925 3700)(-925 3750);
WIRE 16 -1 (-775 3700)(-925 3700);
WIRE 16 -1 (-925 3650)(-925 3700);
WIRE 16 -1 (-775 3650)(-925 3650);
WIRE 16 -1 (-925 3600)(-925 3650);
WIRE 16 -1 (-775 3600)(-925 3600);
WIRE 16 -1 (-925 3550)(-925 3600);
WIRE 16 -1 (-775 3550)(-925 3550);
WIRE 16 -1 (-925 3500)(-925 3550);
WIRE 16 -1 (-775 3500)(-925 3500);
WIRE 16 -1 (-925 3450)(-925 3500);
WIRE 16 -1 (-775 3450)(-925 3450);
WIRE 16 -1 (-925 3400)(-925 3450);
WIRE 16 -1 (-775 3400)(-925 3400);
WIRE 16 -1 (-925 3350)(-925 3400);
WIRE 16 -1 (-775 3350)(-925 3350);
WIRE 16 -1 (-925 3300)(-925 3350);
WIRE 16 -1 (-775 3300)(-925 3300);
WIRE 16 -1 (-925 3250)(-925 3300);
WIRE 16 -1 (-775 3250)(-925 3250);
WIRE 16 -1 (-925 3200)(-925 3250);
WIRE 16 -1 (-775 3200)(-925 3200);
WIRE 16 -1 (-925 3150)(-925 3200);
WIRE 16 -1 (-775 3150)(-925 3150);
WIRE 16 -1 (-925 3100)(-925 3150);
WIRE 16 -1 (-775 3100)(-925 3100);
WIRE 16 -1 (-925 3050)(-925 3100);
WIRE 16 -1 (-775 3050)(-925 3050);
WIRE 16 -1 (-925 3000)(-925 3050);
WIRE 16 -1 (-775 3000)(-925 3000);
WIRE 16 -1 (-925 2950)(-925 3000);
WIRE 16 -1 (-775 2950)(-925 2950);
WIRE 16 -1 (-925 2900)(-925 2950);
WIRE 16 -1 (-775 2900)(-925 2900);
WIRE 16 -1 (-925 2850)(-925 2900);
WIRE 16 -1 (-775 2850)(-925 2850);
WIRE 16 -1 (-925 2800)(-925 2850);
WIRE 16 -1 (-775 2800)(-925 2800);
WIRE 16 -1 (-925 2750)(-925 2800);
WIRE 16 -1 (-775 2750)(-925 2750);
WIRE 16 -1 (-925 2700)(-925 2750);
WIRE 16 -1 (-775 2700)(-925 2700);
WIRE 16 -1 (-925 2650)(-925 2700);
WIRE 16 -1 (-775 2650)(-925 2650);
WIRE 16 -1 (-925 2600)(-925 2650);
WIRE 16 -1 (-775 2600)(-925 2600);
WIRE 16 -1 (-925 2550)(-925 2600);
WIRE 16 -1 (-775 2550)(-925 2550);
WIRE 16 -1 (-925 2500)(-925 2550);
WIRE 16 -1 (-775 2500)(-925 2500);
WIRE 16 -1 (-925 2450)(-925 2500);
WIRE 16 -1 (-775 2450)(-925 2450);
WIRE 16 -1 (-925 2400)(-925 2450);
WIRE 16 -1 (-775 2400)(-925 2400);
WIRE 16 -1 (-925 2350)(-925 2400);
WIRE 16 -1 (-775 2350)(-925 2350);
WIRE 16 -1 (-925 2300)(-925 2350);
WIRE 16 -1 (-775 2300)(-925 2300);
WIRE 16 -1 (-925 2250)(-925 2300);
WIRE 16 -1 (-775 2250)(-925 2250);
WIRE 16 -1 (-925 2200)(-925 2250);
WIRE 16 -1 (-775 2200)(-925 2200);
WIRE 16 -1 (-925 2150)(-925 2200);
WIRE 16 -1 (-775 2150)(-925 2150);
WIRE 16 -1 (-925 2100)(-925 2150);
WIRE 16 -1 (-775 2100)(-925 2100);
WIRE 16 -1 (-925 2050)(-925 2100);
WIRE 16 -1 (-775 2050)(-925 2050);
WIRE 16 -1 (-925 2000)(-925 2050);
WIRE 16 -1 (-775 2000)(-925 2000);
WIRE 16 -1 (-925 1950)(-925 2000);
WIRE 16 -1 (-775 1950)(-925 1950);
WIRE 16 -1 (-925 1900)(-925 1950);
WIRE 16 -1 (-775 1900)(-925 1900);
WIRE 16 -1 (-925 1850)(-925 1900);
WIRE 16 -1 (-775 1850)(-925 1850);
WIRE 16 -1 (-925 1800)(-925 1850);
WIRE 16 -1 (-775 1800)(-925 1800);
WIRE 16 -1 (-925 1750)(-925 1800);
WIRE 16 -1 (-775 1750)(-925 1750);
WIRE 16 -1 (-925 1700)(-925 1750);
WIRE 16 -1 (-775 1700)(-925 1700);
WIRE 16 -1 (-925 1650)(-925 1700);
WIRE 16 -1 (-775 1650)(-925 1650);
WIRE 16 -1 (-925 1600)(-925 1650);
WIRE 16 -1 (-775 1600)(-925 1600);
WIRE 16 -1 (-925 1550)(-925 1600);
WIRE 16 -1 (-775 1550)(-925 1550);
WIRE 16 -1 (-925 1500)(-925 1550);
WIRE 16 -1 (-775 1500)(-925 1500);
WIRE 16 -1 (-925 1450)(-925 1500);
WIRE 16 -1 (-775 1450)(-925 1450);
WIRE 16 -1 (-925 1400)(-925 1450);
WIRE 16 -1 (-775 1400)(-925 1400);
WIRE 16 -1 (-925 1350)(-925 1400);
WIRE 16 -1 (-775 1350)(-925 1350);
WIRE 16 -1 (-925 1300)(-925 1350);
WIRE 16 -1 (-775 1300)(-925 1300);
WIRE 16 -1 (-925 1250)(-925 1300);
WIRE 16 -1 (-775 1250)(-925 1250);
WIRE 16 -1 (-925 1200)(-925 1250);
WIRE 16 -1 (-775 1200)(-925 1200);
WIRE 16 -1 (-925 1150)(-925 1200);
WIRE 16 -1 (-775 1150)(-925 1150);
WIRE 16 -1 (-925 1100)(-925 1150);
WIRE 16 -1 (-775 1100)(-925 1100);
WIRE 16 -1 (-925 1050)(-925 1100);
WIRE 16 -1 (-775 1050)(-925 1050);
WIRE 16 -1 (-925 1000)(-925 1050);
WIRE 16 -1 (-775 1000)(-925 1000);
WIRE 16 -1 (-925 950)(-925 1000);
WIRE 16 -1 (-775 950)(-925 950);
WIRE 16 -1 (-925 900)(-925 950);
WIRE 16 -1 (-775 900)(-925 900);
WIRE 16 -1 (-925 850)(-925 900);
WIRE 16 -1 (-775 850)(-925 850);
WIRE 16 -1 (-925 800)(-925 850);
WIRE 16 -1 (-775 800)(-925 800);
WIRE 16 -1 (-925 750)(-925 800);
WIRE 16 -1 (-775 750)(-925 750);
WIRE 16 -1 (-925 700)(-925 750);
WIRE 16 -1 (-775 700)(-925 700);
WIRE 16 -1 (-925 525)(-925 700);
WIRE 16 -1 (425 4650)(600 4650);
WIRE 16 -1 (600 4650)(600 4600);
WIRE 16 -1 (425 4600)(600 4600);
WIRE 16 -1 (600 4550)(600 4600);
WIRE 16 -1 (425 4550)(600 4550);
WIRE 16 -1 (600 4500)(600 4550);
WIRE 16 -1 (425 4500)(600 4500);
WIRE 16 -1 (600 4450)(600 4500);
WIRE 16 -1 (425 4450)(600 4450);
WIRE 16 -1 (600 4400)(600 4450);
WIRE 16 -1 (425 4400)(600 4400);
WIRE 16 -1 (600 4350)(600 4400);
WIRE 16 -1 (425 4350)(600 4350);
WIRE 16 -1 (600 4300)(600 4350);
WIRE 16 -1 (425 4300)(600 4300);
WIRE 16 -1 (600 4250)(600 4300);
WIRE 16 -1 (425 4250)(600 4250);
WIRE 16 -1 (600 4200)(600 4250);
WIRE 16 -1 (425 4200)(600 4200);
WIRE 16 -1 (600 4150)(600 4200);
WIRE 16 -1 (425 4150)(600 4150);
WIRE 16 -1 (600 4100)(600 4150);
WIRE 16 -1 (425 4100)(600 4100);
WIRE 16 -1 (600 4050)(600 4100);
WIRE 16 -1 (425 4050)(600 4050);
WIRE 16 -1 (600 4000)(600 4050);
WIRE 16 -1 (425 4000)(600 4000);
WIRE 16 -1 (600 3950)(600 4000);
WIRE 16 -1 (425 3950)(600 3950);
WIRE 16 -1 (600 3900)(600 3950);
WIRE 16 -1 (425 3900)(600 3900);
WIRE 16 -1 (600 3850)(600 3900);
WIRE 16 -1 (425 3850)(600 3850);
WIRE 16 -1 (600 3800)(600 3850);
WIRE 16 -1 (425 3800)(600 3800);
WIRE 16 -1 (600 3750)(600 3800);
WIRE 16 -1 (425 3750)(600 3750);
WIRE 16 -1 (600 3700)(600 3750);
WIRE 16 -1 (425 3700)(600 3700);
WIRE 16 -1 (600 3650)(600 3700);
WIRE 16 -1 (425 3650)(600 3650);
WIRE 16 -1 (600 3600)(600 3650);
WIRE 16 -1 (425 3600)(600 3600);
WIRE 16 -1 (600 3550)(600 3600);
WIRE 16 -1 (425 3550)(600 3550);
WIRE 16 -1 (600 3500)(600 3550);
WIRE 16 -1 (425 3500)(600 3500);
WIRE 16 -1 (600 3450)(600 3500);
WIRE 16 -1 (425 3450)(600 3450);
WIRE 16 -1 (600 3400)(600 3450);
WIRE 16 -1 (425 3400)(600 3400);
WIRE 16 -1 (600 3350)(600 3400);
WIRE 16 -1 (425 3350)(600 3350);
WIRE 16 -1 (600 3300)(600 3350);
WIRE 16 -1 (425 3300)(600 3300);
WIRE 16 -1 (600 3250)(600 3300);
WIRE 16 -1 (425 3250)(600 3250);
WIRE 16 -1 (600 3200)(600 3250);
WIRE 16 -1 (425 3200)(600 3200);
WIRE 16 -1 (600 3150)(600 3200);
WIRE 16 -1 (425 3150)(600 3150);
WIRE 16 -1 (600 3100)(600 3150);
WIRE 16 -1 (425 3100)(600 3100);
WIRE 16 -1 (600 3050)(600 3100);
WIRE 16 -1 (425 3050)(600 3050);
WIRE 16 -1 (600 3000)(600 3050);
WIRE 16 -1 (425 3000)(600 3000);
WIRE 16 -1 (600 2950)(600 3000);
WIRE 16 -1 (425 2950)(600 2950);
WIRE 16 -1 (600 2900)(600 2950);
WIRE 16 -1 (425 2900)(600 2900);
WIRE 16 -1 (600 2850)(600 2900);
WIRE 16 -1 (425 2850)(600 2850);
WIRE 16 -1 (600 2800)(600 2850);
WIRE 16 -1 (425 2800)(600 2800);
WIRE 16 -1 (600 2750)(600 2800);
WIRE 16 -1 (425 2750)(600 2750);
WIRE 16 -1 (600 2700)(600 2750);
WIRE 16 -1 (425 2700)(600 2700);
WIRE 16 -1 (600 2650)(600 2700);
WIRE 16 -1 (425 2650)(600 2650);
WIRE 16 -1 (600 2600)(600 2650);
WIRE 16 -1 (425 2600)(600 2600);
WIRE 16 -1 (600 2550)(600 2600);
WIRE 16 -1 (425 2550)(600 2550);
WIRE 16 -1 (600 2500)(600 2550);
WIRE 16 -1 (425 2500)(600 2500);
WIRE 16 -1 (600 2450)(600 2500);
WIRE 16 -1 (425 2450)(600 2450);
WIRE 16 -1 (600 2400)(600 2450);
WIRE 16 -1 (425 2400)(600 2400);
WIRE 16 -1 (600 2350)(600 2400);
WIRE 16 -1 (425 2350)(600 2350);
WIRE 16 -1 (600 2300)(600 2350);
WIRE 16 -1 (425 2300)(600 2300);
WIRE 16 -1 (600 2250)(600 2300);
WIRE 16 -1 (425 2250)(600 2250);
WIRE 16 -1 (600 2200)(600 2250);
WIRE 16 -1 (425 2200)(600 2200);
WIRE 16 -1 (600 2150)(600 2200);
WIRE 16 -1 (425 2150)(600 2150);
WIRE 16 -1 (600 2100)(600 2150);
WIRE 16 -1 (425 2100)(600 2100);
WIRE 16 -1 (600 2050)(600 2100);
WIRE 16 -1 (425 2050)(600 2050);
WIRE 16 -1 (600 2000)(600 2050);
WIRE 16 -1 (425 2000)(600 2000);
WIRE 16 -1 (600 1700)(600 2000);
DOT 1 (-4475 1050);
DOT 1 (-4475 4550);
DOT 1 (-6025 4550);
DOT 1 (-6025 4600);
DOT 1 (-4475 4600);
DOT 1 (-1075 1150);
DOT 1 (-1075 1200);
DOT 1 (-2625 750);
DOT 1 (-4350 1550);
DOT 1 (-4350 1500);
DOT 1 (-4350 1450);
DOT 1 (-6025 1250);
DOT 1 (-4350 1600);
DOT 1 (-4350 1650);
DOT 1 (-4475 1800);
DOT 1 (-4475 1850);
DOT 1 (-2625 4550);
DOT 1 (-2625 4450);
DOT 1 (-2625 4400);
DOT 1 (-2625 4350);
DOT 1 (-2625 4300);
DOT 1 (-2625 4250);
DOT 1 (-2625 4150);
DOT 1 (-2625 4200);
DOT 1 (-2625 4100);
DOT 1 (-2625 4050);
DOT 1 (-2625 4000);
DOT 1 (-2625 3900);
DOT 1 (-2625 3950);
DOT 1 (-2625 3850);
DOT 1 (-2625 3800);
DOT 1 (-2625 3750);
DOT 1 (-2625 3650);
DOT 1 (-2625 3700);
DOT 1 (-2625 3600);
DOT 1 (-2625 3550);
DOT 1 (-2625 3500);
DOT 1 (-2625 3400);
DOT 1 (-2625 3450);
DOT 1 (-2625 3350);
DOT 1 (-2625 3300);
DOT 1 (-2625 3250);
DOT 1 (-2625 3200);
DOT 1 (-2625 3150);
DOT 1 (-2625 3100);
DOT 1 (-2625 3050);
DOT 1 (-2625 3000);
DOT 1 (-2625 2950);
DOT 1 (-2625 2900);
DOT 1 (-2625 2850);
DOT 1 (-2625 2750);
DOT 1 (-2625 2800);
DOT 1 (-2625 2700);
DOT 1 (-2625 2650);
DOT 1 (-2625 2600);
DOT 1 (-2625 2550);
DOT 1 (-2625 2500);
DOT 1 (-2625 2450);
DOT 1 (-2625 2400);
DOT 1 (-2625 2350);
DOT 1 (-2625 2250);
DOT 1 (-2625 2300);
DOT 1 (-2625 2200);
DOT 1 (-2625 2150);
DOT 1 (-2625 2100);
DOT 1 (-2625 2050);
DOT 1 (-2625 2000);
DOT 1 (-2625 1950);
DOT 1 (-2625 1850);
DOT 1 (-2625 1900);
DOT 1 (-2625 1800);
DOT 1 (-2625 1750);
DOT 1 (-2625 1600);
DOT 1 (-2625 1650);
DOT 1 (-2625 1550);
DOT 1 (-2625 1500);
DOT 1 (-2625 1450);
DOT 1 (-2625 1350);
DOT 1 (-2625 1400);
DOT 1 (-2625 1300);
DOT 1 (-2625 1250);
DOT 1 (-2625 1200);
DOT 1 (-2625 1150);
DOT 1 (-2625 1100);
DOT 1 (-2625 1050);
DOT 1 (-2625 1000);
DOT 1 (-2625 950);
DOT 1 (-2625 900);
DOT 1 (-2625 850);
DOT 1 (-2625 800);
DOT 1 (-2625 700);
DOT 1 (-2625 650);
DOT 1 (-4350 4600);
DOT 1 (-4350 4550);
DOT 1 (-4350 4500);
DOT 1 (-4350 4450);
DOT 1 (-4350 4400);
DOT 1 (-4350 4350);
DOT 1 (-4350 4300);
DOT 1 (-4350 4200);
DOT 1 (-4350 4250);
DOT 1 (-4350 4150);
DOT 1 (-4350 4100);
DOT 1 (-4350 4050);
DOT 1 (-4350 3950);
DOT 1 (-4350 4000);
DOT 1 (-4350 3900);
DOT 1 (-4350 3850);
DOT 1 (-4350 3800);
DOT 1 (-4350 3700);
DOT 1 (-4350 3650);
DOT 1 (-4350 3600);
DOT 1 (-4350 3550);
DOT 1 (-4350 3450);
DOT 1 (-4350 3500);
DOT 1 (-4350 3400);
DOT 1 (-4350 3350);
DOT 1 (-4350 3300);
DOT 1 (-4350 3250);
DOT 1 (-4350 3200);
DOT 1 (-4350 3150);
DOT 1 (-4350 3100);
DOT 1 (-4350 3050);
DOT 1 (-4350 2950);
DOT 1 (-4350 2900);
DOT 1 (-4350 2800);
DOT 1 (-4350 2850);
DOT 1 (-4350 2750);
DOT 1 (-4350 2700);
DOT 1 (-4350 2650);
DOT 1 (-4350 2600);
DOT 1 (-4350 2550);
DOT 1 (-4350 2500);
DOT 1 (-4350 2450);
DOT 1 (-4350 2400);
DOT 1 (-4350 2300);
DOT 1 (-4350 2350);
DOT 1 (-4350 2250);
DOT 1 (-4350 2200);
DOT 1 (-4350 2150);
DOT 1 (-4350 2100);
DOT 1 (-4350 2050);
DOT 1 (-4350 2000);
DOT 1 (-4350 1900);
DOT 1 (-4350 1950);
DOT 1 (-4350 1800);
DOT 1 (-4350 1750);
DOT 1 (-4350 1700);
DOT 1 (-4350 1400);
DOT 1 (-4350 1350);
DOT 1 (-4350 1300);
DOT 1 (-4350 1250);
DOT 1 (-4350 1200);
DOT 1 (-4350 1150);
DOT 1 (-4350 1100);
DOT 1 (-4350 1050);
DOT 1 (-4350 1000);
DOT 1 (-4350 950);
DOT 1 (-4350 900);
DOT 1 (-4350 850);
DOT 1 (-4350 750);
DOT 1 (-4350 800);
DOT 1 (-4350 700);
DOT 1 (-6025 4500);
DOT 1 (-6025 4450);
DOT 1 (-6025 4400);
DOT 1 (-6025 4350);
DOT 1 (-6025 4300);
DOT 1 (-6025 4250);
DOT 1 (-6025 4200);
DOT 1 (-6025 4100);
DOT 1 (-6025 4150);
DOT 1 (-6025 4050);
DOT 1 (-6025 4000);
DOT 1 (-6025 3950);
DOT 1 (-6025 3850);
DOT 1 (-6025 3900);
DOT 1 (-6025 3800);
DOT 1 (-6025 3750);
DOT 1 (-6025 3700);
DOT 1 (-6025 3600);
DOT 1 (-6025 3650);
DOT 1 (-6025 3550);
DOT 1 (-6025 3500);
DOT 1 (-6025 3450);
DOT 1 (-6025 3350);
DOT 1 (-6025 3400);
DOT 1 (-6025 3300);
DOT 1 (-6025 3250);
DOT 1 (-6025 3200);
DOT 1 (-6025 3150);
DOT 1 (-6025 3100);
DOT 1 (-6025 3050);
DOT 1 (-6025 3000);
DOT 1 (-6025 2950);
DOT 1 (-6025 2900);
DOT 1 (-6025 2850);
DOT 1 (-6025 2800);
DOT 1 (-6025 2700);
DOT 1 (-6025 2750);
DOT 1 (-6025 2650);
DOT 1 (-6025 2600);
DOT 1 (-6025 2550);
DOT 1 (-6025 2500);
DOT 1 (-6025 2450);
DOT 1 (-6025 2400);
DOT 1 (-6025 2350);
DOT 1 (-6025 2300);
DOT 1 (-6025 2200);
DOT 1 (-6025 2250);
DOT 1 (-6025 2150);
DOT 1 (-6025 2100);
DOT 1 (-6025 2050);
DOT 1 (-6025 2000);
DOT 1 (-6025 1950);
DOT 1 (-6025 1900);
DOT 1 (-6025 1800);
DOT 1 (-6025 1850);
DOT 1 (-6025 1750);
DOT 1 (-6025 1700);
DOT 1 (-6025 1650);
DOT 1 (-6025 1550);
DOT 1 (-6025 1600);
DOT 1 (-6025 1500);
DOT 1 (-6025 1450);
DOT 1 (-6025 1400);
DOT 1 (-6025 1300);
DOT 1 (-6025 1350);
DOT 1 (-6025 1200);
DOT 1 (-6025 1150);
DOT 1 (-6025 1100);
DOT 1 (-6025 1050);
DOT 1 (-6025 1000);
DOT 1 (-6025 950);
DOT 1 (-6025 900);
DOT 1 (-6025 850);
DOT 1 (-6025 800);
DOT 1 (-6025 750);
DOT 1 (-6025 700);
DOT 1 (-1075 3250);
DOT 1 (-1075 3150);
DOT 1 (-1075 3200);
DOT 1 (-1075 3100);
DOT 1 (-1075 3000);
DOT 1 (-1075 3050);
DOT 1 (-1075 2900);
DOT 1 (-1075 2950);
DOT 1 (-1075 2850);
DOT 1 (-1075 2800);
DOT 1 (-1075 2750);
DOT 1 (-1075 2650);
DOT 1 (-1075 2700);
DOT 1 (-1075 2550);
DOT 1 (-1075 2500);
DOT 1 (-1075 2350);
DOT 1 (-1075 2400);
DOT 1 (-1075 2450);
DOT 1 (-1075 2300);
DOT 1 (-1075 2250);
DOT 1 (-1075 2100);
DOT 1 (-1075 2150);
DOT 1 (-1075 2200);
DOT 1 (-1075 2000);
DOT 1 (-1075 2050);
DOT 1 (-1075 1950);
DOT 1 (-1075 1850);
DOT 1 (-1075 1900);
DOT 1 (-1075 1750);
DOT 1 (-1075 1800);
DOT 1 (-1075 1700);
DOT 1 (-1075 1600);
DOT 1 (-1075 1650);
DOT 1 (-1075 1450);
DOT 1 (-1075 1550);
DOT 1 (-1075 1500);
DOT 1 (-1075 1400);
DOT 1 (-1075 1350);
DOT 1 (-1075 1300);
DOT 1 (-1075 1250);
DOT 1 (-1075 1100);
DOT 1 (-1075 1050);
DOT 1 (-1075 950);
DOT 1 (-1075 1000);
DOT 1 (-1075 850);
DOT 1 (-1075 900);
DOT 1 (-1075 800);
DOT 1 (-1075 750);
DOT 1 (-1075 700);
DOT 1 (-1075 650);
DOT 1 (-2800 4600);
DOT 1 (-2800 4450);
DOT 1 (-2800 4550);
DOT 1 (-2800 4500);
DOT 1 (-2800 4350);
DOT 1 (-2800 4400);
DOT 1 (-2800 4300);
DOT 1 (-2800 4200);
DOT 1 (-2800 4250);
DOT 1 (-2800 4100);
DOT 1 (-2800 4150);
DOT 1 (-2800 4050);
DOT 1 (-2800 3950);
DOT 1 (-2800 4000);
DOT 1 (-2800 3850);
DOT 1 (-2800 3900);
DOT 1 (-2800 3700);
DOT 1 (-2800 3750);
DOT 1 (-2800 3650);
DOT 1 (-2800 3450);
DOT 1 (-2800 3500);
DOT 1 (-2800 3300);
DOT 1 (-2800 3400);
DOT 1 (-2800 3350);
DOT 1 (-2800 3200);
DOT 1 (-2800 3250);
DOT 1 (-2800 3150);
DOT 1 (-2800 3050);
DOT 1 (-2800 3100);
DOT 1 (-2800 2950);
DOT 1 (-2800 3000);
DOT 1 (-2800 2900);
DOT 1 (-2800 2850);
DOT 1 (-2800 2800);
DOT 1 (-2800 2650);
DOT 1 (-2800 2700);
DOT 1 (-2800 2750);
DOT 1 (-2800 2600);
DOT 1 (-2800 2550);
DOT 1 (-2800 2400);
DOT 1 (-2800 2450);
DOT 1 (-2800 2500);
DOT 1 (-2800 2350);
DOT 1 (-2800 2300);
DOT 1 (-2800 2150);
DOT 1 (-2800 2200);
DOT 1 (-2800 2250);
DOT 1 (-2800 2050);
DOT 1 (-2800 2100);
DOT 1 (-2800 2000);
DOT 1 (-2800 1900);
DOT 1 (-2800 1800);
DOT 1 (-2800 1850);
DOT 1 (-2800 1750);
DOT 1 (-2800 1650);
DOT 1 (-2800 1700);
DOT 1 (-2800 1500);
DOT 1 (-2800 1450);
DOT 1 (-2800 1400);
DOT 1 (-2800 1250);
DOT 1 (-2800 1350);
DOT 1 (-2800 1300);
DOT 1 (-2800 1150);
DOT 1 (-2800 1200);
DOT 1 (-2800 1100);
DOT 1 (-2800 1000);
DOT 1 (-2800 1050);
DOT 1 (-2800 900);
DOT 1 (-2800 950);
DOT 1 (-2800 850);
DOT 1 (-2800 800);
DOT 1 (-2800 750);
DOT 1 (-2800 700);
DOT 1 (-4475 4500);
DOT 1 (-4475 4350);
DOT 1 (-4475 4450);
DOT 1 (-4475 4400);
DOT 1 (-4475 4250);
DOT 1 (-4475 4300);
DOT 1 (-4475 4200);
DOT 1 (-4475 4100);
DOT 1 (-4475 4150);
DOT 1 (-4475 4000);
DOT 1 (-4475 4050);
DOT 1 (-4475 3950);
DOT 1 (-4475 3850);
DOT 1 (-4475 3900);
DOT 1 (-4475 3750);
DOT 1 (-4475 3800);
DOT 1 (-4475 3700);
DOT 1 (-4475 3600);
DOT 1 (-4475 3650);
DOT 1 (-4475 3450);
DOT 1 (-4475 3550);
DOT 1 (-4475 3500);
DOT 1 (-4475 3350);
DOT 1 (-4475 3200);
DOT 1 (-4475 3300);
DOT 1 (-4475 3250);
DOT 1 (-4475 3100);
DOT 1 (-4475 3150);
DOT 1 (-4475 3050);
DOT 1 (-4475 2950);
DOT 1 (-4475 3000);
DOT 1 (-4475 2850);
DOT 1 (-4475 2900);
DOT 1 (-4475 2800);
DOT 1 (-4475 2750);
DOT 1 (-4475 2700);
DOT 1 (-4475 2550);
DOT 1 (-4475 2600);
DOT 1 (-4475 2650);
DOT 1 (-4475 2500);
DOT 1 (-4475 2450);
DOT 1 (-4475 2300);
DOT 1 (-4475 2350);
DOT 1 (-4475 2400);
DOT 1 (-4475 2250);
DOT 1 (-4475 2200);
DOT 1 (-4475 2050);
DOT 1 (-4475 2100);
DOT 1 (-4475 2150);
DOT 1 (-4475 1950);
DOT 1 (-4475 2000);
DOT 1 (-4475 1900);
DOT 1 (-4475 1700);
DOT 1 (-4475 1750);
DOT 1 (-4475 1550);
DOT 1 (-4475 1600);
DOT 1 (-4475 1400);
DOT 1 (-4475 1500);
DOT 1 (-4475 1450);
DOT 1 (-4475 1350);
DOT 1 (-4475 1300);
DOT 1 (-4475 1150);
DOT 1 (-4475 1250);
DOT 1 (-4475 1200);
DOT 1 (-4475 1100);
DOT 1 (-4475 1000);
DOT 1 (-4475 900);
DOT 1 (-4475 950);
DOT 1 (-4475 800);
DOT 1 (-4475 850);
DOT 1 (-4475 750);
DOT 1 (-4475 700);
DOT 1 (-1075 3300);
DOT 1 (-1075 3450);
DOT 1 (-1075 3400);
DOT 1 (-1075 3550);
DOT 1 (-1075 3500);
DOT 1 (-1075 3600);
DOT 1 (-1075 3700);
DOT 1 (-1075 3650);
DOT 1 (-1075 3750);
DOT 1 (-1075 3800);
DOT 1 (-1075 3850);
DOT 1 (-1075 3950);
DOT 1 (-1075 3900);
DOT 1 (-1075 4000);
DOT 1 (-1075 4050);
DOT 1 (-1075 4100);
DOT 1 (-1075 4150);
DOT 1 (-1075 4300);
DOT 1 (-1075 4350);
DOT 1 (-1075 4250);
DOT 1 (-1075 4400);
DOT 1 (-1075 4450);
DOT 1 (-1075 4550);
DOT 1 (-1075 4500);
DOT 1 (-4475 1650);
DOT 1 (-2800 1550);
DOT 1 (-2800 1600);
DOT 1 (-2625 1700);
DOT 1 (-2800 3550);
DOT 1 (-4350 3750);
DOT 1 (-2800 1950);
DOT 1 (-4350 3000);
DOT 1 (-4475 3400);
DOT 1 (-2625 4500);
DOT 1 (-2800 3600);
DOT 1 (-925 4600);
DOT 1 (600 4600);
DOT 1 (-925 4550);
DOT 1 (600 4550);
DOT 1 (-925 4500);
DOT 1 (600 4500);
DOT 1 (-925 4450);
DOT 1 (600 4450);
DOT 1 (-925 4400);
DOT 1 (600 4400);
DOT 1 (-925 4350);
DOT 1 (600 4350);
DOT 1 (-925 4300);
DOT 1 (600 4300);
DOT 1 (-925 4250);
DOT 1 (600 4250);
DOT 1 (-925 4200);
DOT 1 (-925 4150);
DOT 1 (600 4150);
DOT 1 (-925 4100);
DOT 1 (600 4100);
DOT 1 (600 4050);
DOT 1 (-925 4000);
DOT 1 (600 4000);
DOT 1 (-925 3950);
DOT 1 (600 3950);
DOT 1 (-925 3900);
DOT 1 (600 3900);
DOT 1 (-925 3850);
DOT 1 (600 3850);
DOT 1 (-925 3800);
DOT 1 (600 3800);
DOT 1 (-925 3750);
DOT 1 (600 3750);
DOT 1 (-925 3700);
DOT 1 (600 3700);
DOT 1 (-925 3650);
DOT 1 (600 3650);
DOT 1 (-925 3600);
DOT 1 (600 3600);
DOT 1 (-925 3550);
DOT 1 (600 3550);
DOT 1 (-925 3500);
DOT 1 (600 3500);
DOT 1 (-925 3450);
DOT 1 (600 3450);
DOT 1 (-925 3400);
DOT 1 (600 3400);
DOT 1 (-925 3350);
DOT 1 (600 3350);
DOT 1 (-925 3300);
DOT 1 (600 3300);
DOT 1 (-925 3250);
DOT 1 (600 3250);
DOT 1 (-925 3200);
DOT 1 (600 3200);
DOT 1 (-925 3150);
DOT 1 (600 3150);
DOT 1 (-925 3100);
DOT 1 (600 3100);
DOT 1 (-925 3050);
DOT 1 (600 3050);
DOT 1 (-925 3000);
DOT 1 (600 3000);
DOT 1 (-925 2950);
DOT 1 (600 2950);
DOT 1 (-925 2900);
DOT 1 (600 2900);
DOT 1 (-925 2850);
DOT 1 (600 2850);
DOT 1 (-925 2800);
DOT 1 (600 2800);
DOT 1 (-925 2750);
DOT 1 (600 2750);
DOT 1 (-925 2700);
DOT 1 (600 2700);
DOT 1 (-925 2650);
DOT 1 (600 2650);
DOT 1 (-925 2600);
DOT 1 (600 2600);
DOT 1 (-925 2550);
DOT 1 (600 2550);
DOT 1 (-925 2500);
DOT 1 (600 2500);
DOT 1 (600 2450);
DOT 1 (-925 2400);
DOT 1 (600 2400);
DOT 1 (-925 2350);
DOT 1 (600 2350);
DOT 1 (-925 2300);
DOT 1 (600 2300);
DOT 1 (-925 2250);
DOT 1 (-925 2200);
DOT 1 (600 2200);
DOT 1 (-925 2150);
DOT 1 (600 2150);
DOT 1 (-925 2100);
DOT 1 (600 2100);
DOT 1 (-925 2050);
DOT 1 (600 2050);
DOT 1 (-925 2000);
DOT 1 (-925 1950);
DOT 1 (-925 1900);
DOT 1 (-925 1850);
DOT 1 (-925 1800);
DOT 1 (-925 1750);
DOT 1 (-925 1700);
DOT 1 (-925 1650);
DOT 1 (-925 1600);
DOT 1 (-925 1550);
DOT 1 (-925 1500);
DOT 1 (-925 1450);
DOT 1 (-925 1400);
DOT 1 (-925 1350);
DOT 1 (-925 1300);
DOT 1 (-925 1250);
DOT 1 (-925 1200);
DOT 1 (-925 1150);
DOT 1 (-925 1100);
DOT 1 (-925 1050);
DOT 1 (-925 1000);
DOT 1 (-925 950);
DOT 1 (-925 900);
DOT 1 (-925 850);
DOT 1 (-925 800);
DOT 1 (-925 750);
DOT 1 (-925 700);
DOT 1 (-1075 2600);
DOT 1 (-925 2450);
DOT 1 (600 4200);
DOT 1 (-1075 3350);
DOT 1 (600 2000);
DOT 1 (-2800 3800);
DOT 1 (-1075 4200);
DOT 1 (-925 4050);
DOT 1 (600 2250);
DOT 1 (-4350 1850);
FORCENOTE
ROOM=CPU0
(-6375 400) 0;
DISPLAY LEFT (-6375 400);
DISPLAY 1.723404 (-6375 400);
PAINT PURPLE (-6375 400);
FORCENOTE
BOM_COST=PROC_SOCKET
(-6375 275) 0;
DISPLAY LEFT (-6375 275);
DISPLAY 1.723404 (-6375 275);
PAINT PURPLE (-6375 275);
QUIT
